FILE_TYPE = MACRO_DRAWING;
SET COLOR_WIRE YELLOW;
SET COLOR_PROP MONO;
SET COLOR_DOT WHITE;
SET COLOR_ARC YELLOW;
SET COLOR_BODY GREEN;
SET COLOR_NOTE MONO;
SET PROP_DISPLAY VALUE;
SET PAGE_NUMBER P76;
FORCEADD CAP_A..1
(-1275 4450);
FORCEPROP 1 LAST VOLTAGE 4V
J 0
(-1225 4450);
DISPLAY 0.617021 (-1225 4450);
PAINT SKYBLUE (-1225 4450);
FORCEPROP 1 LAST LOCATION C3D21
J 0
(-1225 4550);
DISPLAY 0.617021 (-1225 4550);
PAINT AQUA (-1225 4550);
FORCEPROP 1 LAST PART_NUMBER E15431-004
J 0
(-1225 4300);
DISPLAY 0.617021 (-1225 4300);
PAINT BLUE (-1225 4300);
FORCEPROP 1 LASTPIN (-1275 4350) $PN 2
J 0
(-1265 4330);
DISPLAY 0.617021 (-1265 4330);
PAINT GREEN (-1265 4330);
FORCEPROP 1 LASTPIN (-1275 4550) $PN 1
J 0
(-1265 4530);
DISPLAY 0.617021 (-1265 4530);
PAINT GREEN (-1265 4530);
FORCEPROP 1 LAST MATERIAL X6S
J 0
(-1225 4350);
DISPLAY 0.617021 (-1225 4350);
PAINT SKYBLUE (-1225 4350);
FORCEPROP 1 LAST PACK_TYPE 0603V
J 0
(-1225 4250);
DISPLAY 0.617021 (-1225 4250);
PAINT SKYBLUE (-1225 4250);
FORCEPROP 1 LAST TOLERANCE 20%
J 0
(-1225 4400);
DISPLAY 0.617021 (-1225 4400);
PAINT SKYBLUE (-1225 4400);
FORCEPROP 1 LAST VALUE 22.0UF
J 0
(-1225 4500);
DISPLAY 0.617021 (-1225 4500);
PAINT SKYBLUE (-1225 4500);
FORCEPROP 0 LAST GROUP PWR_MCP_CAP
J 0
(-1225 4200);
DISPLAY 0.638298 (-1225 4200);
PAINT BROWN (-1225 4200);
DISPLAY BOTH (-1225 4200);
FORCEPROP 2 LAST ROOM PVCCIN_CPU1_DECAP_VR
J 0
(-1225 4550);
PAINT ORANGE (-1225 4550);
DISPLAY INVISIBLE (-1225 4550);
FORCEPROP 1 LAST PATH I1
J 0
(-1225 4600);
DISPLAY 0.978723 (-1225 4600);
PAINT WHITE (-1225 4600);
DISPLAY INVISIBLE (-1225 4600);
FORCEPROP 2 LAST $SEC 1
J 0
(-1225 4650);
PAINT MONO (-1225 4650);
DISPLAY INVISIBLE (-1225 4650);
FORCEPROP 2 LAST CDS_SEC 1
J 0
(-1225 4650);
PAINT MONO (-1225 4650);
DISPLAY INVISIBLE (-1225 4650);
FORCEPROP 2 LAST CDS_LIB dev_discrete
J 0
(-1275 4450);
PAINT ORANGE (-1275 4450);
DISPLAY INVISIBLE (-1275 4450);
FORCEPROP 2 LAST BOM_COST PROC
J 0
(-1275 4450);
PAINT MONO (-1275 4450);
DISPLAY INVISIBLE (-1275 4450);
FORCEPROP 2 LAST CDS_LOCATION C3D21
J 0
(-1225 4550);
DISPLAY 0.617021 (-1225 4550);
PAINT AQUA (-1225 4550);
DISPLAY INVISIBLE (-1225 4550);
FORCEADD CAP_A..1
(-3250 4450);
FORCEPROP 1 LAST TOLERANCE 20%
J 0
(-3200 4400);
DISPLAY 0.617021 (-3200 4400);
PAINT SKYBLUE (-3200 4400);
FORCEPROP 1 LAST VALUE 22.0UF
J 0
(-3200 4500);
DISPLAY 0.617021 (-3200 4500);
PAINT SKYBLUE (-3200 4500);
FORCEPROP 1 LAST LOCATION C2D40
J 0
(-3200 4550);
DISPLAY 0.617021 (-3200 4550);
PAINT AQUA (-3200 4550);
FORCEPROP 1 LAST PACK_TYPE 0603V
J 0
(-3200 4250);
DISPLAY 0.617021 (-3200 4250);
PAINT SKYBLUE (-3200 4250);
FORCEPROP 1 LAST PART_NUMBER E15431-004
J 0
(-3200 4300);
DISPLAY 0.617021 (-3200 4300);
PAINT BLUE (-3200 4300);
FORCEPROP 1 LAST VOLTAGE 4V
J 0
(-3200 4450);
DISPLAY 0.617021 (-3200 4450);
PAINT SKYBLUE (-3200 4450);
FORCEPROP 1 LAST MATERIAL X6S
J 0
(-3200 4350);
DISPLAY 0.617021 (-3200 4350);
PAINT SKYBLUE (-3200 4350);
FORCEPROP 1 LASTPIN (-3250 4550) $PN 1
J 0
(-3240 4530);
DISPLAY 0.617021 (-3240 4530);
PAINT GREEN (-3240 4530);
FORCEPROP 1 LASTPIN (-3250 4350) $PN 2
J 0
(-3240 4330);
DISPLAY 0.617021 (-3240 4330);
PAINT GREEN (-3240 4330);
FORCEPROP 0 LAST GROUP PWR_MCP_CAP
J 0
(-3200 4150);
DISPLAY 0.638298 (-3200 4150);
PAINT BROWN (-3200 4150);
DISPLAY BOTH (-3200 4150);
FORCEPROP 2 LAST CDS_LOCATION C2D40
J 0
(-3200 4550);
DISPLAY 0.617021 (-3200 4550);
PAINT AQUA (-3200 4550);
DISPLAY INVISIBLE (-3200 4550);
FORCEPROP 2 LAST BOM_COST PROC
J 0
(-3250 4450);
PAINT MONO (-3250 4450);
DISPLAY INVISIBLE (-3250 4450);
FORCEPROP 2 LAST CDS_LIB dev_discrete
J 0
(-3250 4450);
PAINT ORANGE (-3250 4450);
DISPLAY INVISIBLE (-3250 4450);
FORCEPROP 2 LAST CDS_SEC 1
J 0
(-3200 4650);
PAINT MONO (-3200 4650);
DISPLAY INVISIBLE (-3200 4650);
FORCEPROP 2 LAST $SEC 1
J 0
(-3200 4650);
PAINT MONO (-3200 4650);
DISPLAY INVISIBLE (-3200 4650);
FORCEPROP 1 LAST PATH I10
J 0
(-3200 4600);
DISPLAY 0.978723 (-3200 4600);
PAINT WHITE (-3200 4600);
DISPLAY INVISIBLE (-3200 4600);
FORCEPROP 2 LAST ROOM PVCCIN_CPU1_DECAP_VR
J 0
(-3200 4550);
PAINT ORANGE (-3200 4550);
DISPLAY INVISIBLE (-3200 4550);
FORCEADD CAP..1
(-5950 1500);
FORCEPROP 1 LASTPIN (-5950 1400) $PN 2
J 0
(-5940 1380);
DISPLAY 0.617021 (-5940 1380);
PAINT GREEN (-5940 1380);
FORCEPROP 1 LASTPIN (-5950 1600) $PN 1
J 0
(-5940 1580);
DISPLAY 0.617021 (-5940 1580);
PAINT GREEN (-5940 1580);
FORCEPROP 1 LAST LOCATION C8P19
J 0
(-5900 1650);
DISPLAY 0.617021 (-5900 1650);
PAINT AQUA (-5900 1650);
FORCEPROP 1 LAST VALUE 47UF
J 0
(-5900 1600);
DISPLAY 0.617021 (-5900 1600);
PAINT SKYBLUE (-5900 1600);
FORCEPROP 1 LAST VOLTAGE 4V
J 0
(-5900 1550);
DISPLAY 0.638298 (-5900 1550);
PAINT SKYBLUE (-5900 1550);
FORCEPROP 1 LAST PART_NUMBER C95333-006
R 1
J 0
(-6000 1400);
DISPLAY 0.617021 (-6000 1400);
PAINT BLUE (-6000 1400);
FORCEPROP 1 LAST TOLERANCE 20%
J 0
(-5900 1500);
DISPLAY 0.617021 (-5900 1500);
PAINT SKYBLUE (-5900 1500);
FORCEPROP 0 LAST GROUP PWR_MLCC_CAP
J 0
(-5894 1337);
DISPLAY 0.638298 (-5894 1337);
PAINT BROWN (-5894 1337);
DISPLAY BOTH (-5894 1337);
FORCEPROP 1 LAST PACK_TYPE 0805
J 0
(-5900 1400);
DISPLAY 0.617021 (-5900 1400);
PAINT SKYBLUE (-5900 1400);
FORCEPROP 1 LAST MATERIAL X6S
J 0
(-5900 1450);
DISPLAY 0.638298 (-5900 1450);
PAINT SKYBLUE (-5900 1450);
FORCEPROP 2 LAST ROOM PVCCIN_CPU1_DECAP_VR
J 0
(-5900 1600);
PAINT ORANGE (-5900 1600);
DISPLAY INVISIBLE (-5900 1600);
FORCEPROP 1 LAST PATH I103
J 0
(-5900 1650);
DISPLAY 0.978723 (-5900 1650);
PAINT WHITE (-5900 1650);
DISPLAY INVISIBLE (-5900 1650);
FORCEPROP 2 LAST CDS_LOCATION C8P19
J 0
(-5900 1600);
DISPLAY 0.617021 (-5900 1600);
PAINT AQUA (-5900 1600);
DISPLAY INVISIBLE (-5900 1600);
FORCEPROP 2 LAST $SEC 1
J 0
(-5900 1700);
DISPLAY 0.680851 (-5900 1700);
PAINT MONO (-5900 1700);
DISPLAY INVISIBLE (-5900 1700);
FORCEPROP 2 LAST CDS_SEC 1
J 0
(-5900 1700);
DISPLAY 1.021277 (-5900 1700);
PAINT ORANGE (-5900 1700);
DISPLAY INVISIBLE (-5900 1700);
FORCEPROP 2 LAST BOM_COST PROC
J 0
(-5950 1500);
PAINT MONO (-5950 1500);
DISPLAY INVISIBLE (-5950 1500);
FORCEPROP 2 LAST CDS_LIB mstr_discrete
J 0
(-5950 1500);
PAINT ORANGE (-5950 1500);
DISPLAY INVISIBLE (-5950 1500);
FORCEADD CAP..1
(-5950 800);
FORCEPROP 1 LAST VALUE 47UF
J 0
(-5900 900);
DISPLAY 0.617021 (-5900 900);
PAINT SKYBLUE (-5900 900);
FORCEPROP 1 LAST PACK_TYPE 0805
J 0
(-5900 700);
DISPLAY 0.617021 (-5900 700);
PAINT SKYBLUE (-5900 700);
FORCEPROP 1 LAST MATERIAL X6S
J 0
(-5900 750);
DISPLAY 0.638298 (-5900 750);
PAINT SKYBLUE (-5900 750);
FORCEPROP 1 LAST TOLERANCE 20%
J 0
(-5900 800);
DISPLAY 0.617021 (-5900 800);
PAINT SKYBLUE (-5900 800);
FORCEPROP 1 LASTPIN (-5950 700) $PN 2
J 0
(-5940 680);
DISPLAY 0.617021 (-5940 680);
PAINT GREEN (-5940 680);
FORCEPROP 1 LAST VOLTAGE 4V
J 0
(-5900 850);
DISPLAY 0.638298 (-5900 850);
PAINT SKYBLUE (-5900 850);
FORCEPROP 1 LASTPIN (-5950 900) $PN 1
J 0
(-5940 880);
DISPLAY 0.617021 (-5940 880);
PAINT GREEN (-5940 880);
FORCEPROP 1 LAST LOCATION C8P12
J 0
(-5900 950);
DISPLAY 0.617021 (-5900 950);
PAINT AQUA (-5900 950);
FORCEPROP 0 LAST GROUP PWR_MLCC_CAP
J 0
(-5894 637);
DISPLAY 0.638298 (-5894 637);
PAINT BROWN (-5894 637);
DISPLAY BOTH (-5894 637);
FORCEPROP 1 LAST PART_NUMBER C95333-006
R 1
J 0
(-6000 700);
DISPLAY 0.617021 (-6000 700);
PAINT BLUE (-6000 700);
FORCEPROP 2 LAST BOM_COST PROC
J 0
(-5950 800);
PAINT MONO (-5950 800);
DISPLAY INVISIBLE (-5950 800);
FORCEPROP 2 LAST CDS_LIB mstr_discrete
J 0
(-5950 800);
PAINT ORANGE (-5950 800);
DISPLAY INVISIBLE (-5950 800);
FORCEPROP 2 LAST CDS_SEC 1
J 0
(-5900 1000);
DISPLAY 1.021277 (-5900 1000);
PAINT ORANGE (-5900 1000);
DISPLAY INVISIBLE (-5900 1000);
FORCEPROP 2 LAST $SEC 1
J 0
(-5900 1000);
DISPLAY 0.680851 (-5900 1000);
PAINT MONO (-5900 1000);
DISPLAY INVISIBLE (-5900 1000);
FORCEPROP 2 LAST CDS_LOCATION C8P12
J 0
(-5900 900);
DISPLAY 0.617021 (-5900 900);
PAINT AQUA (-5900 900);
DISPLAY INVISIBLE (-5900 900);
FORCEPROP 1 LAST PATH I107
J 0
(-5900 950);
DISPLAY 0.978723 (-5900 950);
PAINT WHITE (-5900 950);
DISPLAY INVISIBLE (-5900 950);
FORCEPROP 2 LAST ROOM PVCCIN_CPU1_DECAP_VR
J 0
(-5900 900);
PAINT ORANGE (-5900 900);
DISPLAY INVISIBLE (-5900 900);
FORCEADD CAP_A..1
(-6750 3750);
FORCEPROP 0 LAST GROUP PWR_MLCC_CAP
J 0
(-6694 3562);
DISPLAY 0.638298 (-6694 3562);
PAINT BROWN (-6694 3562);
DISPLAY BOTH (-6694 3562);
FORCEPROP 1 LAST TOLERANCE 20%
J 0
(-6700 3750);
DISPLAY 0.617021 (-6700 3750);
PAINT SKYBLUE (-6700 3750);
FORCEPROP 1 LAST MATERIAL X6S
J 0
(-6700 3700);
DISPLAY 0.617021 (-6700 3700);
PAINT SKYBLUE (-6700 3700);
FORCEPROP 1 LAST PART_NUMBER E15431-004
J 0
(-6700 3650);
DISPLAY 0.617021 (-6700 3650);
PAINT BLUE (-6700 3650);
FORCEPROP 1 LAST PACK_TYPE 0603V
J 0
(-6700 3600);
DISPLAY 0.617021 (-6700 3600);
PAINT SKYBLUE (-6700 3600);
FORCEPROP 1 LASTPIN (-6750 3850) $PN 1
J 0
(-6740 3830);
DISPLAY 0.617021 (-6740 3830);
PAINT GREEN (-6740 3830);
FORCEPROP 1 LASTPIN (-6750 3650) $PN 2
J 0
(-6740 3630);
DISPLAY 0.617021 (-6740 3630);
PAINT GREEN (-6740 3630);
FORCEPROP 1 LAST VOLTAGE 4V
J 0
(-6700 3800);
DISPLAY 0.617021 (-6700 3800);
PAINT SKYBLUE (-6700 3800);
FORCEPROP 1 LAST VALUE 22.0UF
J 0
(-6700 3850);
DISPLAY 0.617021 (-6700 3850);
PAINT SKYBLUE (-6700 3850);
FORCEPROP 1 LAST LOCATION C2D26
J 0
(-6700 3900);
DISPLAY 0.617021 (-6700 3900);
PAINT AQUA (-6700 3900);
FORCEPROP 2 LAST ROOM PVCCIN_CPU1_DECAP_VR
J 0
(-6700 3850);
PAINT ORANGE (-6700 3850);
DISPLAY INVISIBLE (-6700 3850);
FORCEPROP 1 LAST PATH I108
J 0
(-6700 3900);
DISPLAY 0.978723 (-6700 3900);
PAINT WHITE (-6700 3900);
DISPLAY INVISIBLE (-6700 3900);
FORCEPROP 2 LAST $SEC 1
J 0
(-6700 3950);
PAINT MONO (-6700 3950);
DISPLAY INVISIBLE (-6700 3950);
FORCEPROP 2 LAST CDS_SEC 1
J 0
(-6700 3950);
PAINT MONO (-6700 3950);
DISPLAY INVISIBLE (-6700 3950);
FORCEPROP 2 LAST CDS_LIB dev_discrete
J 0
(-6750 3750);
PAINT ORANGE (-6750 3750);
DISPLAY INVISIBLE (-6750 3750);
FORCEPROP 2 LAST BOM_COST PROC
J 0
(-6750 3750);
PAINT MONO (-6750 3750);
DISPLAY INVISIBLE (-6750 3750);
FORCEPROP 2 LAST CDS_LOCATION C2D26
J 0
(-6700 3850);
DISPLAY 0.617021 (-6700 3850);
PAINT AQUA (-6700 3850);
DISPLAY INVISIBLE (-6700 3850);
FORCEADD GND..1
(-7750 3475);
FORCEPROP 3 LASTPIN (-7750 3525) SIG_NAME GND\g
J 0
(-7740 3535);
DISPLAY 0.659574 (-7740 3535);
PAINT MONO (-7740 3535);
DISPLAY INVISIBLE (-7740 3535);
FORCEPROP 1 LAST VOLTAGE 0
J 0
(-7750 3475);
PAINT SKYBLUE (-7750 3475);
DISPLAY INVISIBLE (-7750 3475);
FORCEPROP 2 LAST CDS_LIB mstr_symbols
J 0
(-7750 3475);
PAINT ORANGE (-7750 3475);
DISPLAY INVISIBLE (-7750 3475);
FORCEPROP 1 LAST SIZE 1B
J 0
(-7675 3425);
DISPLAY 0.893617 (-7675 3425);
PAINT GREEN (-7675 3425);
DISPLAY INVISIBLE (-7675 3425);
FORCEPROP 1 LAST BODY_TYPE PLUMBING
J 0
(-7795 3432);
DISPLAY 0.340426 (-7795 3432);
PAINT GREEN (-7795 3432);
DISPLAY INVISIBLE (-7795 3432);
FORCEPROP 1 LAST PATH I109
J 0
(-7675 3475);
DISPLAY 0.872340 (-7675 3475);
PAINT AQUA (-7675 3475);
DISPLAY INVISIBLE (-7675 3475);
FORCEPROP 2 LAST ROOM PVCCIN_CPU1_DECAP_VR
J 0
(-8300 3550);
PAINT ORANGE (-8300 3550);
DISPLAY INVISIBLE (-8300 3550);
FORCEPROP 1 LAST HDL_POWER GND
J 0
(-7750 3625);
DISPLAY 0.893617 (-7750 3625);
PAINT GREEN (-7750 3625);
DISPLAY INVISIBLE (-7750 3625);
FORCEADD CAP_A..1
(-6750 3050);
FORCEPROP 1 LAST TOLERANCE 20%
J 0
(-6700 3050);
DISPLAY 0.617021 (-6700 3050);
PAINT SKYBLUE (-6700 3050);
FORCEPROP 1 LAST VALUE 22.0UF
J 0
(-6700 3150);
DISPLAY 0.617021 (-6700 3150);
PAINT SKYBLUE (-6700 3150);
FORCEPROP 1 LASTPIN (-6750 2950) $PN 2
J 0
(-6740 2930);
DISPLAY 0.617021 (-6740 2930);
PAINT GREEN (-6740 2930);
FORCEPROP 1 LAST MATERIAL X6S
J 0
(-6700 3000);
DISPLAY 0.617021 (-6700 3000);
PAINT SKYBLUE (-6700 3000);
FORCEPROP 1 LAST VOLTAGE 4V
J 0
(-6700 3100);
DISPLAY 0.617021 (-6700 3100);
PAINT SKYBLUE (-6700 3100);
FORCEPROP 1 LAST LOCATION C2D23
J 0
(-6700 3200);
DISPLAY 0.617021 (-6700 3200);
PAINT AQUA (-6700 3200);
FORCEPROP 1 LASTPIN (-6750 3150) $PN 1
J 0
(-6740 3130);
DISPLAY 0.617021 (-6740 3130);
PAINT GREEN (-6740 3130);
FORCEPROP 0 LAST GROUP PWR_MLCC_CAP
J 0
(-6694 2812);
DISPLAY 0.638298 (-6694 2812);
PAINT BROWN (-6694 2812);
DISPLAY BOTH (-6694 2812);
FORCEPROP 1 LAST PACK_TYPE 0603V
J 0
(-6700 2900);
DISPLAY 0.617021 (-6700 2900);
PAINT SKYBLUE (-6700 2900);
FORCEPROP 1 LAST PART_NUMBER E15431-004
J 0
(-6700 2950);
DISPLAY 0.617021 (-6700 2950);
PAINT BLUE (-6700 2950);
FORCEPROP 2 LAST ROOM PVCCIN_CPU1_DECAP_VR
J 0
(-6700 3150);
PAINT ORANGE (-6700 3150);
DISPLAY INVISIBLE (-6700 3150);
FORCEPROP 1 LAST PATH I112
J 0
(-6700 3200);
DISPLAY 0.978723 (-6700 3200);
PAINT WHITE (-6700 3200);
DISPLAY INVISIBLE (-6700 3200);
FORCEPROP 2 LAST $SEC 1
J 0
(-6700 3250);
PAINT MONO (-6700 3250);
DISPLAY INVISIBLE (-6700 3250);
FORCEPROP 2 LAST CDS_SEC 1
J 0
(-6700 3250);
PAINT MONO (-6700 3250);
DISPLAY INVISIBLE (-6700 3250);
FORCEPROP 2 LAST CDS_LIB dev_discrete
J 0
(-6750 3050);
PAINT ORANGE (-6750 3050);
DISPLAY INVISIBLE (-6750 3050);
FORCEPROP 2 LAST BOM_COST PROC
J 0
(-6750 3050);
PAINT MONO (-6750 3050);
DISPLAY INVISIBLE (-6750 3050);
FORCEPROP 2 LAST CDS_LOCATION C2D23
J 0
(-6700 3150);
DISPLAY 0.617021 (-6700 3150);
PAINT AQUA (-6700 3150);
DISPLAY INVISIBLE (-6700 3150);
FORCEADD GND..1
(-7750 2775);
FORCEPROP 3 LASTPIN (-7750 2825) SIG_NAME GND\g
J 0
(-7740 2835);
DISPLAY 0.659574 (-7740 2835);
PAINT MONO (-7740 2835);
DISPLAY INVISIBLE (-7740 2835);
FORCEPROP 1 LAST VOLTAGE 0
J 0
(-7750 2775);
PAINT SKYBLUE (-7750 2775);
DISPLAY INVISIBLE (-7750 2775);
FORCEPROP 2 LAST CDS_LIB mstr_symbols
J 0
(-7750 2775);
PAINT ORANGE (-7750 2775);
DISPLAY INVISIBLE (-7750 2775);
FORCEPROP 1 LAST SIZE 1B
J 0
(-7675 2725);
DISPLAY 0.893617 (-7675 2725);
PAINT GREEN (-7675 2725);
DISPLAY INVISIBLE (-7675 2725);
FORCEPROP 1 LAST BODY_TYPE PLUMBING
J 0
(-7795 2732);
DISPLAY 0.340426 (-7795 2732);
PAINT GREEN (-7795 2732);
DISPLAY INVISIBLE (-7795 2732);
FORCEPROP 1 LAST PATH I113
J 0
(-7675 2775);
DISPLAY 0.872340 (-7675 2775);
PAINT AQUA (-7675 2775);
DISPLAY INVISIBLE (-7675 2775);
FORCEPROP 2 LAST ROOM PVCCIN_CPU1_DECAP_VR
J 0
(-8300 2850);
PAINT ORANGE (-8300 2850);
DISPLAY INVISIBLE (-8300 2850);
FORCEPROP 1 LAST HDL_POWER GND
J 0
(-7750 2925);
DISPLAY 0.893617 (-7750 2925);
PAINT GREEN (-7750 2925);
DISPLAY INVISIBLE (-7750 2925);
FORCEADD CAP_A..1
(-7050 3050);
FORCEPROP 1 LAST TOLERANCE 20%
J 0
(-7000 3050);
DISPLAY 0.617021 (-7000 3050);
PAINT SKYBLUE (-7000 3050);
FORCEPROP 1 LAST MATERIAL X6S
J 0
(-7000 3000);
DISPLAY 0.617021 (-7000 3000);
PAINT SKYBLUE (-7000 3000);
FORCEPROP 1 LAST VALUE 22.0UF
J 0
(-7000 3150);
DISPLAY 0.617021 (-7000 3150);
PAINT SKYBLUE (-7000 3150);
FORCEPROP 1 LAST LOCATION C2D17
J 0
(-7000 3200);
DISPLAY 0.617021 (-7000 3200);
PAINT AQUA (-7000 3200);
FORCEPROP 1 LAST PART_NUMBER E15431-004
J 0
(-7000 2950);
DISPLAY 0.617021 (-7000 2950);
PAINT BLUE (-7000 2950);
FORCEPROP 1 LAST PACK_TYPE 0603V
J 0
(-7000 2900);
DISPLAY 0.617021 (-7000 2900);
PAINT SKYBLUE (-7000 2900);
FORCEPROP 1 LAST VOLTAGE 4V
J 0
(-7000 3100);
DISPLAY 0.617021 (-7000 3100);
PAINT SKYBLUE (-7000 3100);
FORCEPROP 1 LASTPIN (-7050 3150) $PN 1
J 0
(-7040 3130);
DISPLAY 0.617021 (-7040 3130);
PAINT GREEN (-7040 3130);
FORCEPROP 1 LASTPIN (-7050 2950) $PN 2
J 0
(-7040 2930);
DISPLAY 0.617021 (-7040 2930);
PAINT GREEN (-7040 2930);
FORCEPROP 0 LAST GROUP PWR_MLCC_CAP
J 0
(-6994 2862);
DISPLAY 0.638298 (-6994 2862);
PAINT BROWN (-6994 2862);
DISPLAY BOTH (-6994 2862);
FORCEPROP 2 LAST ROOM PVCCIN_CPU1_DECAP_VR
J 0
(-7000 3150);
PAINT ORANGE (-7000 3150);
DISPLAY INVISIBLE (-7000 3150);
FORCEPROP 1 LAST PATH I114
J 0
(-7000 3200);
DISPLAY 0.978723 (-7000 3200);
PAINT WHITE (-7000 3200);
DISPLAY INVISIBLE (-7000 3200);
FORCEPROP 2 LAST $SEC 1
J 0
(-7000 3250);
PAINT MONO (-7000 3250);
DISPLAY INVISIBLE (-7000 3250);
FORCEPROP 2 LAST CDS_SEC 1
J 0
(-7000 3250);
PAINT MONO (-7000 3250);
DISPLAY INVISIBLE (-7000 3250);
FORCEPROP 2 LAST CDS_LIB dev_discrete
J 0
(-7050 3050);
PAINT ORANGE (-7050 3050);
DISPLAY INVISIBLE (-7050 3050);
FORCEPROP 2 LAST BOM_COST PROC
J 0
(-7050 3050);
PAINT MONO (-7050 3050);
DISPLAY INVISIBLE (-7050 3050);
FORCEPROP 2 LAST CDS_LOCATION C2D17
J 0
(-7000 3150);
DISPLAY 0.617021 (-7000 3150);
PAINT AQUA (-7000 3150);
DISPLAY INVISIBLE (-7000 3150);
FORCEADD CAP..1
(-7150 2200);
FORCEPROP 1 LAST VALUE 47UF
J 0
(-7100 2300);
DISPLAY 0.617021 (-7100 2300);
PAINT SKYBLUE (-7100 2300);
FORCEPROP 1 LAST VOLTAGE 4V
J 0
(-7100 2250);
DISPLAY 0.638298 (-7100 2250);
PAINT SKYBLUE (-7100 2250);
FORCEPROP 1 LAST LOCATION C8P26
J 0
(-7100 2350);
DISPLAY 0.617021 (-7100 2350);
PAINT AQUA (-7100 2350);
FORCEPROP 1 LAST MATERIAL X6S
J 0
(-7100 2150);
DISPLAY 0.638298 (-7100 2150);
PAINT SKYBLUE (-7100 2150);
FORCEPROP 1 LAST PACK_TYPE 0805
J 0
(-7100 2100);
DISPLAY 0.617021 (-7100 2100);
PAINT SKYBLUE (-7100 2100);
FORCEPROP 1 LASTPIN (-7150 2300) $PN 1
J 0
(-7140 2280);
DISPLAY 0.617021 (-7140 2280);
PAINT GREEN (-7140 2280);
FORCEPROP 0 LAST GROUP PWR_MLCC_CAP
J 0
(-7094 2037);
DISPLAY 0.638298 (-7094 2037);
PAINT BROWN (-7094 2037);
DISPLAY BOTH (-7094 2037);
FORCEPROP 1 LASTPIN (-7150 2100) $PN 2
J 0
(-7140 2080);
DISPLAY 0.617021 (-7140 2080);
PAINT GREEN (-7140 2080);
FORCEPROP 1 LAST PART_NUMBER C95333-006
R 1
J 0
(-7200 2100);
DISPLAY 0.617021 (-7200 2100);
PAINT BLUE (-7200 2100);
FORCEPROP 1 LAST TOLERANCE 20%
J 0
(-7100 2200);
DISPLAY 0.617021 (-7100 2200);
PAINT SKYBLUE (-7100 2200);
FORCEPROP 2 LAST CDS_LIB mstr_discrete
J 0
(-7150 2200);
PAINT ORANGE (-7150 2200);
DISPLAY INVISIBLE (-7150 2200);
FORCEPROP 2 LAST BOM_COST PROC
J 0
(-7150 2200);
PAINT MONO (-7150 2200);
DISPLAY INVISIBLE (-7150 2200);
FORCEPROP 2 LAST CDS_SEC 1
J 0
(-7100 2400);
PAINT MONO (-7100 2400);
DISPLAY INVISIBLE (-7100 2400);
FORCEPROP 2 LAST $SEC 1
J 0
(-7100 2400);
PAINT MONO (-7100 2400);
DISPLAY INVISIBLE (-7100 2400);
FORCEPROP 2 LAST CDS_LOCATION C8P26
J 0
(-7100 2300);
DISPLAY 0.617021 (-7100 2300);
PAINT AQUA (-7100 2300);
DISPLAY INVISIBLE (-7100 2300);
FORCEPROP 1 LAST PATH I118
J 0
(-7100 2350);
DISPLAY 0.978723 (-7100 2350);
PAINT WHITE (-7100 2350);
DISPLAY INVISIBLE (-7100 2350);
FORCEPROP 2 LAST ROOM PVCCIN_CPU1_DECAP_VR
J 0
(-7100 2300);
PAINT ORANGE (-7100 2300);
DISPLAY INVISIBLE (-7100 2300);
FORCEADD CAP_A..1
(-7450 3750);
FORCEPROP 0 LAST GROUP PWR_MLCC_CAP
J 0
(-7394 3512);
DISPLAY 0.638298 (-7394 3512);
PAINT BROWN (-7394 3512);
DISPLAY BOTH (-7394 3512);
FORCEPROP 1 LAST MATERIAL X6S
J 0
(-7400 3700);
DISPLAY 0.617021 (-7400 3700);
PAINT SKYBLUE (-7400 3700);
FORCEPROP 1 LASTPIN (-7450 3650) $PN 2
J 0
(-7440 3630);
DISPLAY 0.617021 (-7440 3630);
PAINT GREEN (-7440 3630);
FORCEPROP 1 LASTPIN (-7450 3850) $PN 1
J 0
(-7440 3830);
DISPLAY 0.617021 (-7440 3830);
PAINT GREEN (-7440 3830);
FORCEPROP 1 LAST PACK_TYPE 0603V
J 0
(-7400 3600);
DISPLAY 0.617021 (-7400 3600);
PAINT SKYBLUE (-7400 3600);
FORCEPROP 1 LAST TOLERANCE 20%
J 0
(-7400 3750);
DISPLAY 0.617021 (-7400 3750);
PAINT SKYBLUE (-7400 3750);
FORCEPROP 1 LAST VOLTAGE 4V
J 0
(-7400 3800);
DISPLAY 0.617021 (-7400 3800);
PAINT SKYBLUE (-7400 3800);
FORCEPROP 1 LAST VALUE 22.0UF
J 0
(-7400 3850);
DISPLAY 0.617021 (-7400 3850);
PAINT SKYBLUE (-7400 3850);
FORCEPROP 1 LAST LOCATION C2D37
J 0
(-7400 3900);
DISPLAY 0.617021 (-7400 3900);
PAINT AQUA (-7400 3900);
FORCEPROP 1 LAST PART_NUMBER E15431-004
J 0
(-7400 3650);
DISPLAY 0.617021 (-7400 3650);
PAINT BLUE (-7400 3650);
FORCEPROP 2 LAST ROOM PVCCIN_CPU1_DECAP_VR
J 0
(-7400 3850);
PAINT ORANGE (-7400 3850);
DISPLAY INVISIBLE (-7400 3850);
FORCEPROP 1 LAST PATH I119
J 0
(-7400 3900);
DISPLAY 0.978723 (-7400 3900);
PAINT WHITE (-7400 3900);
DISPLAY INVISIBLE (-7400 3900);
FORCEPROP 2 LAST $SEC 1
J 0
(-7400 3950);
PAINT MONO (-7400 3950);
DISPLAY INVISIBLE (-7400 3950);
FORCEPROP 2 LAST CDS_SEC 1
J 0
(-7400 3950);
PAINT MONO (-7400 3950);
DISPLAY INVISIBLE (-7400 3950);
FORCEPROP 2 LAST CDS_LIB dev_discrete
J 0
(-7450 3750);
PAINT ORANGE (-7450 3750);
DISPLAY INVISIBLE (-7450 3750);
FORCEPROP 2 LAST BOM_COST PROC
J 0
(-7450 3750);
PAINT MONO (-7450 3750);
DISPLAY INVISIBLE (-7450 3750);
FORCEPROP 2 LAST CDS_LOCATION C2D37
J 0
(-7400 3850);
DISPLAY 0.617021 (-7400 3850);
PAINT AQUA (-7400 3850);
DISPLAY INVISIBLE (-7400 3850);
FORCEADD CAP_A..1
(-7750 3750);
FORCEPROP 1 LAST MATERIAL X6S
J 0
(-7700 3700);
DISPLAY 0.617021 (-7700 3700);
PAINT SKYBLUE (-7700 3700);
FORCEPROP 1 LAST PART_NUMBER E15431-004
J 0
(-7700 3650);
DISPLAY 0.617021 (-7700 3650);
PAINT BLUE (-7700 3650);
FORCEPROP 0 LAST GROUP PWR_MLCC_CAP
J 0
(-7694 3562);
DISPLAY 0.638298 (-7694 3562);
PAINT BROWN (-7694 3562);
DISPLAY BOTH (-7694 3562);
FORCEPROP 1 LASTPIN (-7750 3650) $PN 2
J 0
(-7740 3630);
DISPLAY 0.617021 (-7740 3630);
PAINT GREEN (-7740 3630);
FORCEPROP 1 LASTPIN (-7750 3850) $PN 1
J 0
(-7740 3830);
DISPLAY 0.617021 (-7740 3830);
PAINT GREEN (-7740 3830);
FORCEPROP 1 LAST LOCATION C2D34
J 0
(-7700 3900);
DISPLAY 0.617021 (-7700 3900);
PAINT AQUA (-7700 3900);
FORCEPROP 1 LAST VALUE 22.0UF
J 0
(-7700 3850);
DISPLAY 0.617021 (-7700 3850);
PAINT SKYBLUE (-7700 3850);
FORCEPROP 1 LAST VOLTAGE 4V
J 0
(-7700 3800);
DISPLAY 0.617021 (-7700 3800);
PAINT SKYBLUE (-7700 3800);
FORCEPROP 1 LAST TOLERANCE 20%
J 0
(-7700 3750);
DISPLAY 0.617021 (-7700 3750);
PAINT SKYBLUE (-7700 3750);
FORCEPROP 1 LAST PACK_TYPE 0603V
J 0
(-7700 3600);
DISPLAY 0.617021 (-7700 3600);
PAINT SKYBLUE (-7700 3600);
FORCEPROP 2 LAST CDS_LOCATION C2D34
J 0
(-7700 3850);
DISPLAY 0.617021 (-7700 3850);
PAINT AQUA (-7700 3850);
DISPLAY INVISIBLE (-7700 3850);
FORCEPROP 2 LAST BOM_COST PROC
J 0
(-7750 3750);
PAINT MONO (-7750 3750);
DISPLAY INVISIBLE (-7750 3750);
FORCEPROP 2 LAST CDS_LIB dev_discrete
J 0
(-7750 3750);
PAINT ORANGE (-7750 3750);
DISPLAY INVISIBLE (-7750 3750);
FORCEPROP 2 LAST CDS_SEC 1
J 0
(-7700 3950);
PAINT MONO (-7700 3950);
DISPLAY INVISIBLE (-7700 3950);
FORCEPROP 2 LAST $SEC 1
J 0
(-7700 3950);
PAINT MONO (-7700 3950);
DISPLAY INVISIBLE (-7700 3950);
FORCEPROP 1 LAST PATH I122
J 0
(-7700 3900);
DISPLAY 0.978723 (-7700 3900);
PAINT WHITE (-7700 3900);
DISPLAY INVISIBLE (-7700 3900);
FORCEPROP 2 LAST ROOM PVCCIN_CPU1_DECAP_VR
J 0
(-7700 3850);
PAINT ORANGE (-7700 3850);
DISPLAY INVISIBLE (-7700 3850);
FORCEADD CAP_A..1
(-7750 3050);
FORCEPROP 1 LAST PART_NUMBER E15431-004
J 0
(-7700 2950);
DISPLAY 0.617021 (-7700 2950);
PAINT BLUE (-7700 2950);
FORCEPROP 1 LAST TOLERANCE 20%
J 0
(-7700 3050);
DISPLAY 0.617021 (-7700 3050);
PAINT SKYBLUE (-7700 3050);
FORCEPROP 1 LAST VALUE 22.0UF
J 0
(-7700 3150);
DISPLAY 0.617021 (-7700 3150);
PAINT SKYBLUE (-7700 3150);
FORCEPROP 1 LAST LOCATION C2D16
J 0
(-7700 3200);
DISPLAY 0.617021 (-7700 3200);
PAINT AQUA (-7700 3200);
FORCEPROP 1 LAST VOLTAGE 4V
J 0
(-7700 3100);
DISPLAY 0.617021 (-7700 3100);
PAINT SKYBLUE (-7700 3100);
FORCEPROP 1 LAST MATERIAL X6S
J 0
(-7700 3000);
DISPLAY 0.617021 (-7700 3000);
PAINT SKYBLUE (-7700 3000);
FORCEPROP 1 LAST PACK_TYPE 0603V
J 0
(-7700 2900);
DISPLAY 0.617021 (-7700 2900);
PAINT SKYBLUE (-7700 2900);
FORCEPROP 1 LASTPIN (-7750 3150) $PN 1
J 0
(-7740 3130);
DISPLAY 0.617021 (-7740 3130);
PAINT GREEN (-7740 3130);
FORCEPROP 1 LASTPIN (-7750 2950) $PN 2
J 0
(-7740 2930);
DISPLAY 0.617021 (-7740 2930);
PAINT GREEN (-7740 2930);
FORCEPROP 0 LAST GROUP PWR_MLCC_CAP
J 0
(-7694 2862);
DISPLAY 0.638298 (-7694 2862);
PAINT BROWN (-7694 2862);
DISPLAY BOTH (-7694 2862);
FORCEPROP 2 LAST CDS_LOCATION C2D16
J 0
(-7700 3150);
DISPLAY 0.617021 (-7700 3150);
PAINT AQUA (-7700 3150);
DISPLAY INVISIBLE (-7700 3150);
FORCEPROP 2 LAST BOM_COST PROC
J 0
(-7750 3050);
PAINT MONO (-7750 3050);
DISPLAY INVISIBLE (-7750 3050);
FORCEPROP 2 LAST CDS_LIB dev_discrete
J 0
(-7750 3050);
PAINT ORANGE (-7750 3050);
DISPLAY INVISIBLE (-7750 3050);
FORCEPROP 2 LAST CDS_SEC 1
J 0
(-7700 3250);
PAINT MONO (-7700 3250);
DISPLAY INVISIBLE (-7700 3250);
FORCEPROP 2 LAST $SEC 1
J 0
(-7700 3250);
PAINT MONO (-7700 3250);
DISPLAY INVISIBLE (-7700 3250);
FORCEPROP 1 LAST PATH I124
J 0
(-7700 3200);
DISPLAY 0.978723 (-7700 3200);
PAINT WHITE (-7700 3200);
DISPLAY INVISIBLE (-7700 3200);
FORCEPROP 2 LAST ROOM PVCCIN_CPU1_DECAP_VR
J 0
(-7700 3150);
PAINT ORANGE (-7700 3150);
DISPLAY INVISIBLE (-7700 3150);
FORCEADD CAP..1
(-7450 2200);
FORCEPROP 1 LAST VOLTAGE 4V
J 0
(-7400 2250);
DISPLAY 0.638298 (-7400 2250);
PAINT SKYBLUE (-7400 2250);
FORCEPROP 0 LAST GROUP PWR_MLCC_CAP
J 0
(-7394 1962);
DISPLAY 0.638298 (-7394 1962);
PAINT BROWN (-7394 1962);
DISPLAY BOTH (-7394 1962);
FORCEPROP 1 LASTPIN (-7450 2100) $PN 2
J 0
(-7440 2080);
DISPLAY 0.617021 (-7440 2080);
PAINT GREEN (-7440 2080);
FORCEPROP 1 LASTPIN (-7450 2300) $PN 1
J 0
(-7440 2280);
DISPLAY 0.617021 (-7440 2280);
PAINT GREEN (-7440 2280);
FORCEPROP 1 LAST LOCATION C8P29
J 0
(-7400 2350);
DISPLAY 0.617021 (-7400 2350);
PAINT AQUA (-7400 2350);
FORCEPROP 1 LAST VALUE 47UF
J 0
(-7400 2300);
DISPLAY 0.617021 (-7400 2300);
PAINT SKYBLUE (-7400 2300);
FORCEPROP 1 LAST PACK_TYPE 0805
J 0
(-7400 2100);
DISPLAY 0.617021 (-7400 2100);
PAINT SKYBLUE (-7400 2100);
FORCEPROP 1 LAST MATERIAL X6S
J 0
(-7400 2150);
DISPLAY 0.638298 (-7400 2150);
PAINT SKYBLUE (-7400 2150);
FORCEPROP 1 LAST PART_NUMBER C95333-006
R 1
J 0
(-7500 2100);
DISPLAY 0.617021 (-7500 2100);
PAINT BLUE (-7500 2100);
FORCEPROP 1 LAST TOLERANCE 20%
J 0
(-7400 2200);
DISPLAY 0.617021 (-7400 2200);
PAINT SKYBLUE (-7400 2200);
FORCEPROP 2 LAST CDS_LIB mstr_discrete
J 0
(-7450 2200);
PAINT ORANGE (-7450 2200);
DISPLAY INVISIBLE (-7450 2200);
FORCEPROP 2 LAST BOM_COST PROC
J 0
(-7450 2200);
PAINT MONO (-7450 2200);
DISPLAY INVISIBLE (-7450 2200);
FORCEPROP 2 LAST CDS_SEC 1
J 0
(-7400 2400);
PAINT MONO (-7400 2400);
DISPLAY INVISIBLE (-7400 2400);
FORCEPROP 2 LAST $SEC 1
J 0
(-7400 2400);
PAINT MONO (-7400 2400);
DISPLAY INVISIBLE (-7400 2400);
FORCEPROP 2 LAST CDS_LOCATION C8P29
J 0
(-7400 2300);
DISPLAY 0.617021 (-7400 2300);
PAINT AQUA (-7400 2300);
DISPLAY INVISIBLE (-7400 2300);
FORCEPROP 1 LAST PATH I125
J 0
(-7400 2350);
DISPLAY 0.978723 (-7400 2350);
PAINT WHITE (-7400 2350);
DISPLAY INVISIBLE (-7400 2350);
FORCEPROP 2 LAST ROOM PVCCIN_CPU1_DECAP_VR
J 0
(-7375 2300);
PAINT ORANGE (-7375 2300);
DISPLAY INVISIBLE (-7375 2300);
FORCEADD CAP..1
(-7750 2200);
FORCEPROP 1 LAST VALUE 47UF
J 0
(-7700 2300);
DISPLAY 0.617021 (-7700 2300);
PAINT SKYBLUE (-7700 2300);
FORCEPROP 1 LAST VOLTAGE 4V
J 0
(-7700 2250);
DISPLAY 0.638298 (-7700 2250);
PAINT SKYBLUE (-7700 2250);
FORCEPROP 0 LAST GROUP PWR_MLCC_CAP
J 0
(-7694 2037);
DISPLAY 0.638298 (-7694 2037);
PAINT BROWN (-7694 2037);
DISPLAY BOTH (-7694 2037);
FORCEPROP 1 LASTPIN (-7750 2300) $PN 1
J 0
(-7740 2280);
DISPLAY 0.617021 (-7740 2280);
PAINT GREEN (-7740 2280);
FORCEPROP 1 LAST LOCATION C8P10
J 0
(-7700 2350);
DISPLAY 0.617021 (-7700 2350);
PAINT AQUA (-7700 2350);
FORCEPROP 1 LAST MATERIAL X6S
J 0
(-7700 2150);
DISPLAY 0.617021 (-7700 2150);
PAINT SKYBLUE (-7700 2150);
FORCEPROP 1 LAST PART_NUMBER C95333-006
R 1
J 0
(-7800 2100);
DISPLAY 0.617021 (-7800 2100);
PAINT BLUE (-7800 2100);
FORCEPROP 1 LASTPIN (-7750 2100) $PN 2
J 0
(-7740 2080);
DISPLAY 0.617021 (-7740 2080);
PAINT GREEN (-7740 2080);
FORCEPROP 1 LAST PACK_TYPE 0805
J 0
(-7700 2100);
DISPLAY 0.617021 (-7700 2100);
PAINT SKYBLUE (-7700 2100);
FORCEPROP 1 LAST TOLERANCE 20%
J 0
(-7700 2200);
DISPLAY 0.617021 (-7700 2200);
PAINT SKYBLUE (-7700 2200);
FORCEPROP 2 LAST CDS_LIB mstr_discrete
J 0
(-7750 2200);
PAINT ORANGE (-7750 2200);
DISPLAY INVISIBLE (-7750 2200);
FORCEPROP 2 LAST BOM_COST PROC
J 0
(-7750 2200);
PAINT MONO (-7750 2200);
DISPLAY INVISIBLE (-7750 2200);
FORCEPROP 2 LAST CDS_SEC 1
J 0
(-7700 2400);
PAINT MONO (-7700 2400);
DISPLAY INVISIBLE (-7700 2400);
FORCEPROP 2 LAST $SEC 1
J 0
(-7700 2400);
PAINT MONO (-7700 2400);
DISPLAY INVISIBLE (-7700 2400);
FORCEPROP 2 LAST CDS_LOCATION C8P10
J 0
(-7700 2300);
DISPLAY 0.617021 (-7700 2300);
PAINT AQUA (-7700 2300);
DISPLAY INVISIBLE (-7700 2300);
FORCEPROP 1 LAST PATH I127
J 0
(-7700 2350);
DISPLAY 0.978723 (-7700 2350);
PAINT WHITE (-7700 2350);
DISPLAY INVISIBLE (-7700 2350);
FORCEPROP 2 LAST ROOM PVCCIN_CPU1_DECAP_VR
J 0
(-7700 2300);
PAINT ORANGE (-7700 2300);
DISPLAY INVISIBLE (-7700 2300);
FORCEADD CAP..1
(-6550 1500);
FORCEPROP 1 LAST VOLTAGE 4V
J 0
(-6500 1550);
DISPLAY 0.638298 (-6500 1550);
PAINT SKYBLUE (-6500 1550);
FORCEPROP 1 LAST VALUE 47UF
J 0
(-6500 1600);
DISPLAY 0.617021 (-6500 1600);
PAINT SKYBLUE (-6500 1600);
FORCEPROP 1 LASTPIN (-6550 1400) $PN 2
J 0
(-6540 1380);
DISPLAY 0.617021 (-6540 1380);
PAINT GREEN (-6540 1380);
FORCEPROP 1 LASTPIN (-6550 1600) $PN 1
J 0
(-6540 1580);
DISPLAY 0.617021 (-6540 1580);
PAINT GREEN (-6540 1580);
FORCEPROP 1 LAST TOLERANCE 20%
J 0
(-6500 1500);
DISPLAY 0.617021 (-6500 1500);
PAINT SKYBLUE (-6500 1500);
FORCEPROP 1 LAST MATERIAL X6S
J 0
(-6500 1450);
DISPLAY 0.638298 (-6500 1450);
PAINT SKYBLUE (-6500 1450);
FORCEPROP 1 LAST PACK_TYPE 0805
J 0
(-6500 1400);
DISPLAY 0.617021 (-6500 1400);
PAINT SKYBLUE (-6500 1400);
FORCEPROP 1 LAST LOCATION C8P16
J 0
(-6500 1650);
DISPLAY 0.617021 (-6500 1650);
PAINT AQUA (-6500 1650);
FORCEPROP 1 LAST PART_NUMBER C95333-006
R 1
J 0
(-6600 1400);
DISPLAY 0.617021 (-6600 1400);
PAINT BLUE (-6600 1400);
FORCEPROP 0 LAST GROUP PWR_MLCC_CAP
J 0
(-6494 1337);
DISPLAY 0.638298 (-6494 1337);
PAINT BROWN (-6494 1337);
DISPLAY BOTH (-6494 1337);
FORCEPROP 2 LAST BOM_COST PROC
J 0
(-6550 1500);
PAINT MONO (-6550 1500);
DISPLAY INVISIBLE (-6550 1500);
FORCEPROP 2 LAST CDS_LIB mstr_discrete
J 0
(-6550 1500);
PAINT ORANGE (-6550 1500);
DISPLAY INVISIBLE (-6550 1500);
FORCEPROP 2 LAST CDS_SEC 1
J 0
(-6500 1700);
DISPLAY 1.021277 (-6500 1700);
PAINT ORANGE (-6500 1700);
DISPLAY INVISIBLE (-6500 1700);
FORCEPROP 2 LAST $SEC 1
J 0
(-6500 1700);
DISPLAY 0.680851 (-6500 1700);
PAINT MONO (-6500 1700);
DISPLAY INVISIBLE (-6500 1700);
FORCEPROP 2 LAST CDS_LOCATION C8P16
J 0
(-6500 1600);
DISPLAY 0.617021 (-6500 1600);
PAINT AQUA (-6500 1600);
DISPLAY INVISIBLE (-6500 1600);
FORCEPROP 1 LAST PATH I129
J 0
(-6500 1650);
DISPLAY 0.978723 (-6500 1650);
PAINT WHITE (-6500 1650);
DISPLAY INVISIBLE (-6500 1650);
FORCEPROP 2 LAST ROOM PVCCIN_CPU1_DECAP_VR
J 0
(-6500 1600);
PAINT ORANGE (-6500 1600);
DISPLAY INVISIBLE (-6500 1600);
FORCEADD GND..1
(-6550 1225);
FORCEPROP 3 LASTPIN (-6550 1275) SIG_NAME GND\g
J 0
(-6540 1285);
DISPLAY 0.659574 (-6540 1285);
PAINT MONO (-6540 1285);
DISPLAY INVISIBLE (-6540 1285);
FORCEPROP 1 LAST PATH I130
J 0
(-6475 1225);
DISPLAY 0.872340 (-6475 1225);
PAINT AQUA (-6475 1225);
DISPLAY INVISIBLE (-6475 1225);
FORCEPROP 1 LAST HDL_POWER GND
J 0
(-6550 1375);
DISPLAY 0.893617 (-6550 1375);
PAINT GREEN (-6550 1375);
DISPLAY INVISIBLE (-6550 1375);
FORCEPROP 2 LAST ROOM PVCCIN_CPU1_DECAP_VR
J 0
(-7100 1300);
PAINT ORANGE (-7100 1300);
DISPLAY INVISIBLE (-7100 1300);
FORCEPROP 1 LAST BODY_TYPE PLUMBING
J 0
(-6595 1182);
DISPLAY 0.340426 (-6595 1182);
PAINT GREEN (-6595 1182);
DISPLAY INVISIBLE (-6595 1182);
FORCEPROP 2 LAST CDS_LIB mstr_symbols
J 0
(-6550 1225);
PAINT ORANGE (-6550 1225);
DISPLAY INVISIBLE (-6550 1225);
FORCEPROP 1 LAST SIZE 1B
J 0
(-6475 1175);
DISPLAY 0.893617 (-6475 1175);
PAINT GREEN (-6475 1175);
DISPLAY INVISIBLE (-6475 1175);
FORCEPROP 1 LAST VOLTAGE 0
J 0
(-6550 1225);
PAINT SKYBLUE (-6550 1225);
DISPLAY INVISIBLE (-6550 1225);
FORCEADD CAP..1
(-7150 1500);
FORCEPROP 1 LASTPIN (-7150 1600) $PN 1
J 0
(-7140 1580);
DISPLAY 0.617021 (-7140 1580);
PAINT GREEN (-7140 1580);
FORCEPROP 1 LAST PACK_TYPE 0805
J 0
(-7100 1400);
DISPLAY 0.617021 (-7100 1400);
PAINT SKYBLUE (-7100 1400);
FORCEPROP 1 LASTPIN (-7150 1400) $PN 2
J 0
(-7140 1380);
DISPLAY 0.617021 (-7140 1380);
PAINT GREEN (-7140 1380);
FORCEPROP 1 LAST LOCATION C8P13
J 0
(-7100 1650);
DISPLAY 0.617021 (-7100 1650);
PAINT AQUA (-7100 1650);
FORCEPROP 1 LAST VALUE 47UF
J 0
(-7100 1600);
DISPLAY 0.617021 (-7100 1600);
PAINT SKYBLUE (-7100 1600);
FORCEPROP 1 LAST VOLTAGE 4V
J 0
(-7100 1550);
DISPLAY 0.638298 (-7100 1550);
PAINT SKYBLUE (-7100 1550);
FORCEPROP 0 LAST GROUP PWR_MLCC_CAP
J 0
(-7094 1337);
DISPLAY 0.638298 (-7094 1337);
PAINT BROWN (-7094 1337);
DISPLAY BOTH (-7094 1337);
FORCEPROP 1 LAST MATERIAL X6S
J 0
(-7100 1450);
DISPLAY 0.638298 (-7100 1450);
PAINT SKYBLUE (-7100 1450);
FORCEPROP 1 LAST PART_NUMBER C95333-006
R 1
J 0
(-7200 1400);
DISPLAY 0.617021 (-7200 1400);
PAINT BLUE (-7200 1400);
FORCEPROP 1 LAST TOLERANCE 20%
J 0
(-7100 1500);
DISPLAY 0.617021 (-7100 1500);
PAINT SKYBLUE (-7100 1500);
FORCEPROP 2 LAST BOM_COST PROC
J 0
(-7150 1500);
PAINT MONO (-7150 1500);
DISPLAY INVISIBLE (-7150 1500);
FORCEPROP 2 LAST CDS_LIB mstr_discrete
J 0
(-7150 1500);
PAINT ORANGE (-7150 1500);
DISPLAY INVISIBLE (-7150 1500);
FORCEPROP 2 LAST CDS_SEC 1
J 0
(-7100 1700);
DISPLAY 1.021277 (-7100 1700);
PAINT ORANGE (-7100 1700);
DISPLAY INVISIBLE (-7100 1700);
FORCEPROP 2 LAST $SEC 1
J 0
(-7100 1700);
DISPLAY 0.680851 (-7100 1700);
PAINT MONO (-7100 1700);
DISPLAY INVISIBLE (-7100 1700);
FORCEPROP 2 LAST CDS_LOCATION C8P13
J 0
(-7100 1600);
DISPLAY 0.617021 (-7100 1600);
PAINT AQUA (-7100 1600);
DISPLAY INVISIBLE (-7100 1600);
FORCEPROP 1 LAST PATH I132
J 0
(-7100 1650);
DISPLAY 0.978723 (-7100 1650);
PAINT WHITE (-7100 1650);
DISPLAY INVISIBLE (-7100 1650);
FORCEPROP 2 LAST ROOM PVCCIN_CPU1_DECAP_VR
J 0
(-7100 1600);
PAINT ORANGE (-7100 1600);
DISPLAY INVISIBLE (-7100 1600);
FORCEADD GND..1
(-7750 525);
FORCEPROP 3 LASTPIN (-7750 575) SIG_NAME GND\g
J 0
(-7740 585);
DISPLAY 0.659574 (-7740 585);
PAINT MONO (-7740 585);
DISPLAY INVISIBLE (-7740 585);
FORCEPROP 1 LAST VOLTAGE 0
J 0
(-7750 525);
PAINT SKYBLUE (-7750 525);
DISPLAY INVISIBLE (-7750 525);
FORCEPROP 2 LAST CDS_LIB mstr_symbols
J 0
(-7750 525);
PAINT ORANGE (-7750 525);
DISPLAY INVISIBLE (-7750 525);
FORCEPROP 1 LAST SIZE 1B
J 0
(-7675 475);
DISPLAY 0.893617 (-7675 475);
PAINT GREEN (-7675 475);
DISPLAY INVISIBLE (-7675 475);
FORCEPROP 1 LAST BODY_TYPE PLUMBING
J 0
(-7795 482);
DISPLAY 0.340426 (-7795 482);
PAINT GREEN (-7795 482);
DISPLAY INVISIBLE (-7795 482);
FORCEPROP 1 LAST PATH I134
J 0
(-7675 525);
DISPLAY 0.872340 (-7675 525);
PAINT AQUA (-7675 525);
DISPLAY INVISIBLE (-7675 525);
FORCEPROP 2 LAST ROOM PVCCIN_CPU1_DECAP_VR
J 0
(-8300 600);
PAINT ORANGE (-8300 600);
DISPLAY INVISIBLE (-8300 600);
FORCEPROP 1 LAST HDL_POWER GND
J 0
(-7750 675);
DISPLAY 0.893617 (-7750 675);
PAINT GREEN (-7750 675);
DISPLAY INVISIBLE (-7750 675);
FORCEADD CAP..1
(-7450 1500);
FORCEPROP 1 LAST LOCATION C8P28
J 0
(-7400 1650);
DISPLAY 0.617021 (-7400 1650);
PAINT AQUA (-7400 1650);
FORCEPROP 1 LAST VALUE 47UF
J 0
(-7400 1600);
DISPLAY 0.617021 (-7400 1600);
PAINT SKYBLUE (-7400 1600);
FORCEPROP 1 LAST VOLTAGE 4V
J 0
(-7400 1550);
DISPLAY 0.638298 (-7400 1550);
PAINT SKYBLUE (-7400 1550);
FORCEPROP 1 LAST MATERIAL X6S
J 0
(-7400 1450);
DISPLAY 0.638298 (-7400 1450);
PAINT SKYBLUE (-7400 1450);
FORCEPROP 1 LASTPIN (-7450 1600) $PN 1
J 0
(-7440 1580);
DISPLAY 0.617021 (-7440 1580);
PAINT GREEN (-7440 1580);
FORCEPROP 1 LASTPIN (-7450 1400) $PN 2
J 0
(-7440 1380);
DISPLAY 0.617021 (-7440 1380);
PAINT GREEN (-7440 1380);
FORCEPROP 0 LAST GROUP PWR_MLCC_CAP
J 0
(-7394 1262);
DISPLAY 0.638298 (-7394 1262);
PAINT BROWN (-7394 1262);
DISPLAY BOTH (-7394 1262);
FORCEPROP 1 LAST PACK_TYPE 0805
J 0
(-7400 1400);
DISPLAY 0.617021 (-7400 1400);
PAINT SKYBLUE (-7400 1400);
FORCEPROP 1 LAST PART_NUMBER C95333-006
R 1
J 0
(-7500 1400);
DISPLAY 0.617021 (-7500 1400);
PAINT BLUE (-7500 1400);
FORCEPROP 1 LAST TOLERANCE 20%
J 0
(-7400 1500);
DISPLAY 0.617021 (-7400 1500);
PAINT SKYBLUE (-7400 1500);
FORCEPROP 2 LAST ROOM PVCCIN_CPU1_DECAP_VR
J 0
(-7375 1600);
PAINT ORANGE (-7375 1600);
DISPLAY INVISIBLE (-7375 1600);
FORCEPROP 1 LAST PATH I137
J 0
(-7400 1650);
DISPLAY 0.978723 (-7400 1650);
PAINT WHITE (-7400 1650);
DISPLAY INVISIBLE (-7400 1650);
FORCEPROP 2 LAST CDS_LOCATION C8P28
J 0
(-7400 1600);
DISPLAY 0.617021 (-7400 1600);
PAINT AQUA (-7400 1600);
DISPLAY INVISIBLE (-7400 1600);
FORCEPROP 2 LAST $SEC 1
J 0
(-7400 1700);
DISPLAY 0.680851 (-7400 1700);
PAINT MONO (-7400 1700);
DISPLAY INVISIBLE (-7400 1700);
FORCEPROP 2 LAST CDS_SEC 1
J 0
(-7400 1700);
DISPLAY 1.021277 (-7400 1700);
PAINT ORANGE (-7400 1700);
DISPLAY INVISIBLE (-7400 1700);
FORCEPROP 2 LAST CDS_LIB mstr_discrete
J 0
(-7450 1500);
PAINT ORANGE (-7450 1500);
DISPLAY INVISIBLE (-7450 1500);
FORCEPROP 2 LAST BOM_COST PROC
J 0
(-7450 1500);
PAINT MONO (-7450 1500);
DISPLAY INVISIBLE (-7450 1500);
FORCEADD CAP..1
(-7750 1500);
FORCEPROP 1 LAST VOLTAGE 4V
J 0
(-7700 1550);
DISPLAY 0.638298 (-7700 1550);
PAINT SKYBLUE (-7700 1550);
FORCEPROP 1 LAST VALUE 47UF
J 0
(-7700 1600);
DISPLAY 0.617021 (-7700 1600);
PAINT SKYBLUE (-7700 1600);
FORCEPROP 1 LAST LOCATION C8P11
J 0
(-7700 1650);
DISPLAY 0.617021 (-7700 1650);
PAINT AQUA (-7700 1650);
FORCEPROP 1 LASTPIN (-7750 1600) $PN 1
J 0
(-7740 1580);
DISPLAY 0.617021 (-7740 1580);
PAINT GREEN (-7740 1580);
FORCEPROP 0 LAST GROUP PWR_MLCC_CAP
J 0
(-7694 1337);
DISPLAY 0.638298 (-7694 1337);
PAINT BROWN (-7694 1337);
DISPLAY BOTH (-7694 1337);
FORCEPROP 1 LAST PACK_TYPE 0805
J 0
(-7700 1400);
DISPLAY 0.617021 (-7700 1400);
PAINT SKYBLUE (-7700 1400);
FORCEPROP 1 LASTPIN (-7750 1400) $PN 2
J 0
(-7740 1380);
DISPLAY 0.617021 (-7740 1380);
PAINT GREEN (-7740 1380);
FORCEPROP 1 LAST PART_NUMBER C95333-006
R 1
J 0
(-7800 1400);
DISPLAY 0.617021 (-7800 1400);
PAINT BLUE (-7800 1400);
FORCEPROP 1 LAST MATERIAL X6S
J 0
(-7700 1450);
DISPLAY 0.638298 (-7700 1450);
PAINT SKYBLUE (-7700 1450);
FORCEPROP 1 LAST TOLERANCE 20%
J 0
(-7700 1500);
DISPLAY 0.617021 (-7700 1500);
PAINT SKYBLUE (-7700 1500);
FORCEPROP 2 LAST CDS_LIB mstr_discrete
J 0
(-7750 1500);
PAINT ORANGE (-7750 1500);
DISPLAY INVISIBLE (-7750 1500);
FORCEPROP 2 LAST BOM_COST PROC
J 0
(-7750 1500);
PAINT MONO (-7750 1500);
DISPLAY INVISIBLE (-7750 1500);
FORCEPROP 2 LAST CDS_SEC 1
J 0
(-7700 1700);
DISPLAY 1.021277 (-7700 1700);
PAINT ORANGE (-7700 1700);
DISPLAY INVISIBLE (-7700 1700);
FORCEPROP 2 LAST $SEC 1
J 0
(-7700 1700);
DISPLAY 0.680851 (-7700 1700);
PAINT MONO (-7700 1700);
DISPLAY INVISIBLE (-7700 1700);
FORCEPROP 2 LAST CDS_LOCATION C8P11
J 0
(-7700 1600);
DISPLAY 0.617021 (-7700 1600);
PAINT AQUA (-7700 1600);
DISPLAY INVISIBLE (-7700 1600);
FORCEPROP 1 LAST PATH I139
J 0
(-7700 1650);
DISPLAY 0.978723 (-7700 1650);
PAINT WHITE (-7700 1650);
DISPLAY INVISIBLE (-7700 1650);
FORCEPROP 2 LAST ROOM PVCCIN_CPU1_DECAP_VR
J 0
(-7700 1600);
PAINT ORANGE (-7700 1600);
DISPLAY INVISIBLE (-7700 1600);
FORCEADD PVCCIN_CPU1..1
(-5900 4750);
FORCEPROP 3 LASTPIN (-5900 4700) SIG_NAME PVCCIN_CPU1\g
J 0
(-5890 4710);
DISPLAY 0.659574 (-5890 4710);
PAINT MONO (-5890 4710);
DISPLAY INVISIBLE (-5890 4710);
FORCEPROP 1 LAST HDL_POWER PVCCIN_CPU1
J 1
(-5900 4800);
DISPLAY 0.872340 (-5900 4800);
PAINT GREEN (-5900 4800);
DISPLAY INVISIBLE (-5900 4800);
FORCEPROP 2 LAST ROOM PVCCIN_CPU1_DECAP_VR
J 0
(-5650 4850);
PAINT ORANGE (-5650 4850);
DISPLAY INVISIBLE (-5650 4850);
FORCEPROP 1 LAST PATH I143
J 0
(-5850 4775);
DISPLAY 0.872340 (-5850 4775);
PAINT AQUA (-5850 4775);
DISPLAY INVISIBLE (-5850 4775);
FORCEPROP 1 LAST BODY_TYPE PLUMBING
J 0
(-5945 4707);
DISPLAY 0.340426 (-5945 4707);
PAINT GREEN (-5945 4707);
DISPLAY INVISIBLE (-5945 4707);
FORCEPROP 2 LAST CDS_LIB mstr_symbols
J 0
(-5900 4750);
PAINT ORANGE (-5900 4750);
DISPLAY INVISIBLE (-5900 4750);
FORCEPROP 1 LAST VOLTAGE 2.0V
J 0
(-5945 4707);
DISPLAY 0.340426 (-5945 4707);
PAINT SKYBLUE (-5945 4707);
DISPLAY INVISIBLE (-5945 4707);
FORCEADD PVCCIN_CPU1..1
(-7750 4050);
FORCEPROP 3 LASTPIN (-7750 4000) SIG_NAME PVCCIN_CPU1\g
J 0
(-7740 4010);
DISPLAY 0.659574 (-7740 4010);
PAINT MONO (-7740 4010);
DISPLAY INVISIBLE (-7740 4010);
FORCEPROP 1 LAST HDL_POWER PVCCIN_CPU1
J 1
(-7750 4100);
DISPLAY 0.872340 (-7750 4100);
PAINT GREEN (-7750 4100);
DISPLAY INVISIBLE (-7750 4100);
FORCEPROP 2 LAST ROOM PVCCIN_CPU1_DECAP_VR
J 0
(-7500 4150);
PAINT ORANGE (-7500 4150);
DISPLAY INVISIBLE (-7500 4150);
FORCEPROP 1 LAST PATH I144
J 0
(-7700 4075);
DISPLAY 0.872340 (-7700 4075);
PAINT AQUA (-7700 4075);
DISPLAY INVISIBLE (-7700 4075);
FORCEPROP 1 LAST BODY_TYPE PLUMBING
J 0
(-7795 4007);
DISPLAY 0.340426 (-7795 4007);
PAINT GREEN (-7795 4007);
DISPLAY INVISIBLE (-7795 4007);
FORCEPROP 2 LAST CDS_LIB mstr_symbols
J 0
(-7750 4050);
PAINT ORANGE (-7750 4050);
DISPLAY INVISIBLE (-7750 4050);
FORCEPROP 1 LAST VOLTAGE 2.0V
J 0
(-7795 4007);
DISPLAY 0.340426 (-7795 4007);
PAINT SKYBLUE (-7795 4007);
DISPLAY INVISIBLE (-7795 4007);
FORCEADD PVCCIN_CPU1..1
(-7750 3350);
FORCEPROP 3 LASTPIN (-7750 3300) SIG_NAME PVCCIN_CPU1\g
J 0
(-7740 3310);
DISPLAY 0.659574 (-7740 3310);
PAINT MONO (-7740 3310);
DISPLAY INVISIBLE (-7740 3310);
FORCEPROP 1 LAST HDL_POWER PVCCIN_CPU1
J 1
(-7750 3400);
DISPLAY 0.872340 (-7750 3400);
PAINT GREEN (-7750 3400);
DISPLAY INVISIBLE (-7750 3400);
FORCEPROP 2 LAST ROOM PVCCIN_CPU1_DECAP_VR
J 0
(-7500 3450);
PAINT ORANGE (-7500 3450);
DISPLAY INVISIBLE (-7500 3450);
FORCEPROP 1 LAST PATH I145
J 0
(-7700 3375);
DISPLAY 0.872340 (-7700 3375);
PAINT AQUA (-7700 3375);
DISPLAY INVISIBLE (-7700 3375);
FORCEPROP 1 LAST BODY_TYPE PLUMBING
J 0
(-7795 3307);
DISPLAY 0.340426 (-7795 3307);
PAINT GREEN (-7795 3307);
DISPLAY INVISIBLE (-7795 3307);
FORCEPROP 2 LAST CDS_LIB mstr_symbols
J 0
(-7750 3350);
PAINT ORANGE (-7750 3350);
DISPLAY INVISIBLE (-7750 3350);
FORCEPROP 1 LAST VOLTAGE 2.0V
J 0
(-7795 3307);
DISPLAY 0.340426 (-7795 3307);
PAINT SKYBLUE (-7795 3307);
DISPLAY INVISIBLE (-7795 3307);
FORCEADD PVCCIN_CPU1..1
(-5900 4050);
FORCEPROP 3 LASTPIN (-5900 4000) SIG_NAME PVCCIN_CPU1\g
J 0
(-5890 4010);
DISPLAY 0.659574 (-5890 4010);
PAINT MONO (-5890 4010);
DISPLAY INVISIBLE (-5890 4010);
FORCEPROP 1 LAST VOLTAGE 2.0V
J 0
(-5945 4007);
DISPLAY 0.340426 (-5945 4007);
PAINT SKYBLUE (-5945 4007);
DISPLAY INVISIBLE (-5945 4007);
FORCEPROP 2 LAST CDS_LIB mstr_symbols
J 0
(-5900 4050);
PAINT ORANGE (-5900 4050);
DISPLAY INVISIBLE (-5900 4050);
FORCEPROP 1 LAST BODY_TYPE PLUMBING
J 0
(-5945 4007);
DISPLAY 0.340426 (-5945 4007);
PAINT GREEN (-5945 4007);
DISPLAY INVISIBLE (-5945 4007);
FORCEPROP 1 LAST PATH I146
J 0
(-5850 4075);
DISPLAY 0.872340 (-5850 4075);
PAINT AQUA (-5850 4075);
DISPLAY INVISIBLE (-5850 4075);
FORCEPROP 2 LAST ROOM PVCCIN_CPU1_DECAP_VR
J 0
(-5650 4150);
PAINT ORANGE (-5650 4150);
DISPLAY INVISIBLE (-5650 4150);
FORCEPROP 1 LAST HDL_POWER PVCCIN_CPU1
J 1
(-5900 4100);
DISPLAY 0.872340 (-5900 4100);
PAINT GREEN (-5900 4100);
DISPLAY INVISIBLE (-5900 4100);
FORCEADD PVCCIN_CPU1..1
(-5900 3350);
FORCEPROP 3 LASTPIN (-5900 3300) SIG_NAME PVCCIN_CPU1\g
J 0
(-5890 3310);
DISPLAY 0.659574 (-5890 3310);
PAINT MONO (-5890 3310);
DISPLAY INVISIBLE (-5890 3310);
FORCEPROP 1 LAST VOLTAGE 2.0V
J 0
(-5945 3307);
DISPLAY 0.340426 (-5945 3307);
PAINT SKYBLUE (-5945 3307);
DISPLAY INVISIBLE (-5945 3307);
FORCEPROP 2 LAST CDS_LIB mstr_symbols
J 0
(-5900 3350);
PAINT ORANGE (-5900 3350);
DISPLAY INVISIBLE (-5900 3350);
FORCEPROP 1 LAST BODY_TYPE PLUMBING
J 0
(-5945 3307);
DISPLAY 0.340426 (-5945 3307);
PAINT GREEN (-5945 3307);
DISPLAY INVISIBLE (-5945 3307);
FORCEPROP 1 LAST PATH I147
J 0
(-5850 3375);
DISPLAY 0.872340 (-5850 3375);
PAINT AQUA (-5850 3375);
DISPLAY INVISIBLE (-5850 3375);
FORCEPROP 2 LAST ROOM PVCCIN_CPU1_DECAP_VR
J 0
(-5650 3450);
PAINT ORANGE (-5650 3450);
DISPLAY INVISIBLE (-5650 3450);
FORCEPROP 1 LAST HDL_POWER PVCCIN_CPU1
J 1
(-5900 3400);
DISPLAY 0.872340 (-5900 3400);
PAINT GREEN (-5900 3400);
DISPLAY INVISIBLE (-5900 3400);
FORCEADD CAP_A..1
(-2350 3750);
FORCEPROP 1 LAST VALUE 22.0UF
J 0
(-2300 3850);
DISPLAY 0.617021 (-2300 3850);
PAINT SKYBLUE (-2300 3850);
FORCEPROP 1 LAST LOCATION C3D9
J 0
(-2300 3900);
DISPLAY 0.617021 (-2300 3900);
PAINT AQUA (-2300 3900);
FORCEPROP 1 LAST TOLERANCE 20%
J 0
(-2300 3750);
DISPLAY 0.617021 (-2300 3750);
PAINT SKYBLUE (-2300 3750);
FORCEPROP 1 LAST VOLTAGE 4V
J 0
(-2300 3800);
DISPLAY 0.617021 (-2300 3800);
PAINT SKYBLUE (-2300 3800);
FORCEPROP 1 LASTPIN (-2350 3850) $PN 1
J 0
(-2340 3830);
DISPLAY 0.617021 (-2340 3830);
PAINT GREEN (-2340 3830);
FORCEPROP 1 LASTPIN (-2350 3650) $PN 2
J 0
(-2340 3630);
DISPLAY 0.617021 (-2340 3630);
PAINT GREEN (-2340 3630);
FORCEPROP 0 LAST GROUP PWR_MLCC_CAP
J 0
(-2294 3512);
DISPLAY 0.638298 (-2294 3512);
PAINT BROWN (-2294 3512);
DISPLAY BOTH (-2294 3512);
FORCEPROP 1 LAST PACK_TYPE 0603V
J 0
(-2300 3600);
DISPLAY 0.617021 (-2300 3600);
PAINT SKYBLUE (-2300 3600);
FORCEPROP 1 LAST PART_NUMBER E15431-004
J 0
(-2300 3650);
DISPLAY 0.617021 (-2300 3650);
PAINT BLUE (-2300 3650);
FORCEPROP 1 LAST MATERIAL X6S
J 0
(-2300 3700);
DISPLAY 0.617021 (-2300 3700);
PAINT SKYBLUE (-2300 3700);
FORCEPROP 2 LAST CDS_LOCATION C3D9
J 0
(-2300 3850);
DISPLAY 0.617021 (-2300 3850);
PAINT AQUA (-2300 3850);
DISPLAY INVISIBLE (-2300 3850);
FORCEPROP 2 LAST BOM_COST PROC
J 0
(-2350 3750);
PAINT MONO (-2350 3750);
DISPLAY INVISIBLE (-2350 3750);
FORCEPROP 2 LAST CDS_LIB dev_discrete
J 0
(-2350 3750);
PAINT ORANGE (-2350 3750);
DISPLAY INVISIBLE (-2350 3750);
FORCEPROP 2 LAST CDS_SEC 1
J 0
(-2300 3950);
PAINT MONO (-2300 3950);
DISPLAY INVISIBLE (-2300 3950);
FORCEPROP 2 LAST $SEC 1
J 0
(-2300 3950);
PAINT MONO (-2300 3950);
DISPLAY INVISIBLE (-2300 3950);
FORCEPROP 1 LAST PATH I15
J 0
(-2300 3900);
DISPLAY 0.978723 (-2300 3900);
PAINT WHITE (-2300 3900);
DISPLAY INVISIBLE (-2300 3900);
FORCEPROP 2 LAST ROOM PVCCIN_CPU1_DECAP_VR
J 0
(-2300 3850);
PAINT ORANGE (-2300 3850);
DISPLAY INVISIBLE (-2300 3850);
FORCEADD PVCCIN_CPU1..1
(-5950 2500);
FORCEPROP 3 LASTPIN (-5950 2450) SIG_NAME PVCCIN_CPU1\g
J 0
(-5940 2460);
DISPLAY 0.659574 (-5940 2460);
PAINT MONO (-5940 2460);
DISPLAY INVISIBLE (-5940 2460);
FORCEPROP 1 LAST VOLTAGE 2.0V
J 0
(-5995 2457);
DISPLAY 0.340426 (-5995 2457);
PAINT SKYBLUE (-5995 2457);
DISPLAY INVISIBLE (-5995 2457);
FORCEPROP 2 LAST CDS_LIB mstr_symbols
J 0
(-5950 2500);
PAINT ORANGE (-5950 2500);
DISPLAY INVISIBLE (-5950 2500);
FORCEPROP 1 LAST BODY_TYPE PLUMBING
J 0
(-5995 2457);
DISPLAY 0.340426 (-5995 2457);
PAINT GREEN (-5995 2457);
DISPLAY INVISIBLE (-5995 2457);
FORCEPROP 2 LAST ROOM PVCCIN_CPU1_DECAP_VR
J 0
(-5700 2600);
PAINT ORANGE (-5700 2600);
DISPLAY INVISIBLE (-5700 2600);
FORCEPROP 1 LAST HDL_POWER PVCCIN_CPU1
J 1
(-5950 2550);
DISPLAY 0.872340 (-5950 2550);
PAINT GREEN (-5950 2550);
DISPLAY INVISIBLE (-5950 2550);
FORCEPROP 1 LAST PATH I153
J 0
(-5900 2525);
DISPLAY 0.872340 (-5900 2525);
PAINT AQUA (-5900 2525);
DISPLAY INVISIBLE (-5900 2525);
FORCEADD PVCCIN_CPU1..1
(-7750 2500);
FORCEPROP 3 LASTPIN (-7750 2450) SIG_NAME PVCCIN_CPU1\g
J 0
(-7740 2460);
DISPLAY 0.659574 (-7740 2460);
PAINT MONO (-7740 2460);
DISPLAY INVISIBLE (-7740 2460);
FORCEPROP 1 LAST VOLTAGE 2.0V
J 0
(-7795 2457);
DISPLAY 0.340426 (-7795 2457);
PAINT SKYBLUE (-7795 2457);
DISPLAY INVISIBLE (-7795 2457);
FORCEPROP 2 LAST CDS_LIB mstr_symbols
J 0
(-7750 2500);
PAINT ORANGE (-7750 2500);
DISPLAY INVISIBLE (-7750 2500);
FORCEPROP 1 LAST BODY_TYPE PLUMBING
J 0
(-7795 2457);
DISPLAY 0.340426 (-7795 2457);
PAINT GREEN (-7795 2457);
DISPLAY INVISIBLE (-7795 2457);
FORCEPROP 1 LAST PATH I154
J 0
(-7700 2525);
DISPLAY 0.872340 (-7700 2525);
PAINT AQUA (-7700 2525);
DISPLAY INVISIBLE (-7700 2525);
FORCEPROP 2 LAST ROOM PVCCIN_CPU1_DECAP_VR
J 0
(-7500 2600);
PAINT ORANGE (-7500 2600);
DISPLAY INVISIBLE (-7500 2600);
FORCEPROP 1 LAST HDL_POWER PVCCIN_CPU1
J 1
(-7750 2550);
DISPLAY 0.872340 (-7750 2550);
PAINT GREEN (-7750 2550);
DISPLAY INVISIBLE (-7750 2550);
FORCEADD PVCCIN_CPU1..1
(-7750 1800);
FORCEPROP 3 LASTPIN (-7750 1750) SIG_NAME PVCCIN_CPU1\g
J 0
(-7740 1760);
DISPLAY 0.659574 (-7740 1760);
PAINT MONO (-7740 1760);
DISPLAY INVISIBLE (-7740 1760);
FORCEPROP 1 LAST PATH I155
J 0
(-7700 1825);
DISPLAY 0.872340 (-7700 1825);
PAINT AQUA (-7700 1825);
DISPLAY INVISIBLE (-7700 1825);
FORCEPROP 1 LAST HDL_POWER PVCCIN_CPU1
J 1
(-7750 1850);
DISPLAY 0.872340 (-7750 1850);
PAINT GREEN (-7750 1850);
DISPLAY INVISIBLE (-7750 1850);
FORCEPROP 2 LAST ROOM PVCCIN_CPU1_DECAP_VR
J 0
(-7500 1900);
PAINT ORANGE (-7500 1900);
DISPLAY INVISIBLE (-7500 1900);
FORCEPROP 1 LAST BODY_TYPE PLUMBING
J 0
(-7795 1757);
DISPLAY 0.340426 (-7795 1757);
PAINT GREEN (-7795 1757);
DISPLAY INVISIBLE (-7795 1757);
FORCEPROP 2 LAST CDS_LIB mstr_symbols
J 0
(-7750 1800);
PAINT ORANGE (-7750 1800);
DISPLAY INVISIBLE (-7750 1800);
FORCEPROP 1 LAST VOLTAGE 2.0V
J 0
(-7795 1757);
DISPLAY 0.340426 (-7795 1757);
PAINT SKYBLUE (-7795 1757);
DISPLAY INVISIBLE (-7795 1757);
FORCEADD PVCCIN_CPU1..1
(-5950 1800);
FORCEPROP 3 LASTPIN (-5950 1750) SIG_NAME PVCCIN_CPU1\g
J 0
(-5940 1760);
DISPLAY 0.659574 (-5940 1760);
PAINT MONO (-5940 1760);
DISPLAY INVISIBLE (-5940 1760);
FORCEPROP 1 LAST PATH I156
J 0
(-5900 1825);
DISPLAY 0.872340 (-5900 1825);
PAINT AQUA (-5900 1825);
DISPLAY INVISIBLE (-5900 1825);
FORCEPROP 1 LAST HDL_POWER PVCCIN_CPU1
J 1
(-5950 1850);
DISPLAY 0.872340 (-5950 1850);
PAINT GREEN (-5950 1850);
DISPLAY INVISIBLE (-5950 1850);
FORCEPROP 2 LAST ROOM PVCCIN_CPU1_DECAP_VR
J 0
(-5700 1900);
PAINT ORANGE (-5700 1900);
DISPLAY INVISIBLE (-5700 1900);
FORCEPROP 1 LAST BODY_TYPE PLUMBING
J 0
(-5995 1757);
DISPLAY 0.340426 (-5995 1757);
PAINT GREEN (-5995 1757);
DISPLAY INVISIBLE (-5995 1757);
FORCEPROP 2 LAST CDS_LIB mstr_symbols
J 0
(-5950 1800);
PAINT ORANGE (-5950 1800);
DISPLAY INVISIBLE (-5950 1800);
FORCEPROP 1 LAST VOLTAGE 2.0V
J 0
(-5995 1757);
DISPLAY 0.340426 (-5995 1757);
PAINT SKYBLUE (-5995 1757);
DISPLAY INVISIBLE (-5995 1757);
FORCEADD PVCCIN_CPU1..1
(-5950 1100);
FORCEPROP 3 LASTPIN (-5950 1050) SIG_NAME PVCCIN_CPU1\g
J 0
(-5940 1060);
DISPLAY 0.659574 (-5940 1060);
PAINT MONO (-5940 1060);
DISPLAY INVISIBLE (-5940 1060);
FORCEPROP 1 LAST VOLTAGE 2.0V
J 0
(-5995 1057);
DISPLAY 0.340426 (-5995 1057);
PAINT SKYBLUE (-5995 1057);
DISPLAY INVISIBLE (-5995 1057);
FORCEPROP 2 LAST CDS_LIB mstr_symbols
J 0
(-5950 1100);
PAINT ORANGE (-5950 1100);
DISPLAY INVISIBLE (-5950 1100);
FORCEPROP 1 LAST BODY_TYPE PLUMBING
J 0
(-5995 1057);
DISPLAY 0.340426 (-5995 1057);
PAINT GREEN (-5995 1057);
DISPLAY INVISIBLE (-5995 1057);
FORCEPROP 2 LAST ROOM PVCCIN_CPU1_DECAP_VR
J 0
(-5700 1200);
PAINT ORANGE (-5700 1200);
DISPLAY INVISIBLE (-5700 1200);
FORCEPROP 1 LAST HDL_POWER PVCCIN_CPU1
J 1
(-5950 1150);
DISPLAY 0.872340 (-5950 1150);
PAINT GREEN (-5950 1150);
DISPLAY INVISIBLE (-5950 1150);
FORCEPROP 1 LAST PATH I157
J 0
(-5900 1125);
DISPLAY 0.872340 (-5900 1125);
PAINT AQUA (-5900 1125);
DISPLAY INVISIBLE (-5900 1125);
FORCEADD PVCCIN_CPU1..1
(-7750 1100);
FORCEPROP 3 LASTPIN (-7750 1050) SIG_NAME PVCCIN_CPU1\g
J 0
(-7740 1060);
DISPLAY 0.659574 (-7740 1060);
PAINT MONO (-7740 1060);
DISPLAY INVISIBLE (-7740 1060);
FORCEPROP 1 LAST VOLTAGE 2.0V
J 0
(-7795 1057);
DISPLAY 0.340426 (-7795 1057);
PAINT SKYBLUE (-7795 1057);
DISPLAY INVISIBLE (-7795 1057);
FORCEPROP 2 LAST CDS_LIB mstr_symbols
J 0
(-7750 1100);
PAINT ORANGE (-7750 1100);
DISPLAY INVISIBLE (-7750 1100);
FORCEPROP 1 LAST BODY_TYPE PLUMBING
J 0
(-7795 1057);
DISPLAY 0.340426 (-7795 1057);
PAINT GREEN (-7795 1057);
DISPLAY INVISIBLE (-7795 1057);
FORCEPROP 1 LAST PATH I158
J 0
(-7700 1125);
DISPLAY 0.872340 (-7700 1125);
PAINT AQUA (-7700 1125);
DISPLAY INVISIBLE (-7700 1125);
FORCEPROP 2 LAST ROOM PVCCIN_CPU1_DECAP_VR
J 0
(-7500 1200);
PAINT ORANGE (-7500 1200);
DISPLAY INVISIBLE (-7500 1200);
FORCEPROP 1 LAST HDL_POWER PVCCIN_CPU1
J 1
(-7750 1150);
DISPLAY 0.872340 (-7750 1150);
PAINT GREEN (-7750 1150);
DISPLAY INVISIBLE (-7750 1150);
FORCEADD CAP_A..1
(-4500 4450);
FORCEPROP 1 LAST TOLERANCE 20%
J 0
(-4450 4450);
DISPLAY 0.617021 (-4450 4450);
PAINT SKYBLUE (-4450 4450);
FORCEPROP 1 LAST PART_NUMBER E15431-004
J 0
(-4450 4350);
DISPLAY 0.617021 (-4450 4350);
PAINT BLUE (-4450 4350);
FORCEPROP 0 LAST GROUP PWR_MLCC_CAP
J 0
(-4444 4262);
DISPLAY 0.638298 (-4444 4262);
PAINT BROWN (-4444 4262);
DISPLAY BOTH (-4444 4262);
FORCEPROP 1 LAST VALUE 22.0UF
J 0
(-4450 4550);
DISPLAY 0.617021 (-4450 4550);
PAINT SKYBLUE (-4450 4550);
FORCEPROP 1 LASTPIN (-4500 4550) $PN 1
J 0
(-4490 4530);
DISPLAY 0.617021 (-4490 4530);
PAINT ORANGE (-4490 4530);
FORCEPROP 1 LASTPIN (-4500 4350) $PN 2
J 0
(-4490 4330);
DISPLAY 0.617021 (-4490 4330);
PAINT ORANGE (-4490 4330);
FORCEPROP 1 LAST PACK_TYPE 0603V
J 0
(-4450 4300);
DISPLAY 0.617021 (-4450 4300);
PAINT SKYBLUE (-4450 4300);
FORCEPROP 1 LAST MATERIAL X6S
J 0
(-4450 4400);
DISPLAY 0.617021 (-4450 4400);
PAINT SKYBLUE (-4450 4400);
FORCEPROP 1 LAST VOLTAGE 4V
J 0
(-4450 4500);
DISPLAY 0.617021 (-4450 4500);
PAINT SKYBLUE (-4450 4500);
FORCEPROP 1 LAST LOCATION C2D15
J 0
(-4450 4600);
DISPLAY 0.617021 (-4450 4600);
PAINT AQUA (-4450 4600);
FORCEPROP 2 LAST ROOM PVCCIN_CPU1_DECAP_VR
J 0
(-4450 4550);
PAINT ORANGE (-4450 4550);
DISPLAY INVISIBLE (-4450 4550);
FORCEPROP 1 LAST PATH I159
J 0
(-4450 4600);
DISPLAY 0.978723 (-4450 4600);
PAINT WHITE (-4450 4600);
DISPLAY INVISIBLE (-4450 4600);
FORCEPROP 2 LAST $SEC 1
J 0
(-4450 4650);
PAINT MONO (-4450 4650);
DISPLAY INVISIBLE (-4450 4650);
FORCEPROP 2 LAST CDS_SEC 1
J 0
(-4450 4650);
PAINT MONO (-4450 4650);
DISPLAY INVISIBLE (-4450 4650);
FORCEPROP 2 LAST CDS_LIB dev_discrete
J 0
(-4500 4450);
PAINT ORANGE (-4500 4450);
DISPLAY INVISIBLE (-4500 4450);
FORCEPROP 2 LAST BOM_COST PROC
J 0
(-4500 4450);
PAINT MONO (-4500 4450);
DISPLAY INVISIBLE (-4500 4450);
FORCEPROP 2 LAST CDS_LOCATION C2D15
J 0
(-4450 4550);
DISPLAY 0.617021 (-4450 4550);
PAINT AQUA (-4450 4550);
DISPLAY INVISIBLE (-4450 4550);
FORCEADD GND..1
(-3850 3475);
FORCEPROP 3 LASTPIN (-3850 3525) SIG_NAME GND\g
J 0
(-3840 3535);
DISPLAY 0.659574 (-3840 3535);
PAINT MONO (-3840 3535);
DISPLAY INVISIBLE (-3840 3535);
FORCEPROP 1 LAST HDL_POWER GND
J 0
(-3850 3625);
DISPLAY 0.893617 (-3850 3625);
PAINT GREEN (-3850 3625);
DISPLAY INVISIBLE (-3850 3625);
FORCEPROP 2 LAST ROOM PVCCIN_CPU1_DECAP_VR
J 0
(-4400 3550);
PAINT ORANGE (-4400 3550);
DISPLAY INVISIBLE (-4400 3550);
FORCEPROP 1 LAST PATH I16
J 0
(-3775 3475);
DISPLAY 0.872340 (-3775 3475);
PAINT AQUA (-3775 3475);
DISPLAY INVISIBLE (-3775 3475);
FORCEPROP 1 LAST BODY_TYPE PLUMBING
J 0
(-3895 3432);
DISPLAY 0.340426 (-3895 3432);
PAINT GREEN (-3895 3432);
DISPLAY INVISIBLE (-3895 3432);
FORCEPROP 1 LAST SIZE 1B
J 0
(-3775 3425);
DISPLAY 0.893617 (-3775 3425);
PAINT GREEN (-3775 3425);
DISPLAY INVISIBLE (-3775 3425);
FORCEPROP 2 LAST CDS_LIB mstr_symbols
J 0
(-3850 3475);
PAINT ORANGE (-3850 3475);
DISPLAY INVISIBLE (-3850 3475);
FORCEPROP 1 LAST VOLTAGE 0
J 0
(-3850 3475);
PAINT SKYBLUE (-3850 3475);
DISPLAY INVISIBLE (-3850 3475);
FORCEADD CAP_A..1
(-4400 3750);
FORCEPROP 1 LAST PART_NUMBER E15431-004
J 0
(-4350 3650);
DISPLAY 0.617021 (-4350 3650);
PAINT BLUE (-4350 3650);
FORCEPROP 1 LAST LOCATION C2D38
J 0
(-4350 3900);
DISPLAY 0.617021 (-4350 3900);
PAINT AQUA (-4350 3900);
FORCEPROP 1 LAST VALUE 22.0UF
J 0
(-4350 3850);
DISPLAY 0.617021 (-4350 3850);
PAINT SKYBLUE (-4350 3850);
FORCEPROP 1 LAST PACK_TYPE 0603V
J 0
(-4350 3600);
DISPLAY 0.617021 (-4350 3600);
PAINT SKYBLUE (-4350 3600);
FORCEPROP 1 LASTPIN (-4400 3650) $PN 2
J 0
(-4390 3630);
DISPLAY 0.617021 (-4390 3630);
PAINT ORANGE (-4390 3630);
FORCEPROP 1 LASTPIN (-4400 3850) $PN 1
J 0
(-4390 3830);
DISPLAY 0.617021 (-4390 3830);
PAINT ORANGE (-4390 3830);
FORCEPROP 1 LAST TOLERANCE 20%
J 0
(-4350 3750);
DISPLAY 0.617021 (-4350 3750);
PAINT SKYBLUE (-4350 3750);
FORCEPROP 1 LAST MATERIAL X6S
J 0
(-4350 3700);
DISPLAY 0.617021 (-4350 3700);
PAINT SKYBLUE (-4350 3700);
FORCEPROP 1 LAST VOLTAGE 4V
J 0
(-4350 3800);
DISPLAY 0.617021 (-4350 3800);
PAINT SKYBLUE (-4350 3800);
FORCEPROP 0 LAST GROUP PWR_MLCC_CAP
J 0
(-4344 3512);
DISPLAY 0.638298 (-4344 3512);
PAINT BROWN (-4344 3512);
DISPLAY BOTH (-4344 3512);
FORCEPROP 2 LAST ROOM PVCCIN_CPU1_DECAP_VR
J 0
(-4350 3850);
PAINT ORANGE (-4350 3850);
DISPLAY INVISIBLE (-4350 3850);
FORCEPROP 1 LAST PATH I160
J 0
(-4350 3900);
DISPLAY 0.978723 (-4350 3900);
PAINT WHITE (-4350 3900);
DISPLAY INVISIBLE (-4350 3900);
FORCEPROP 2 LAST $SEC 1
J 0
(-4350 3950);
PAINT MONO (-4350 3950);
DISPLAY INVISIBLE (-4350 3950);
FORCEPROP 2 LAST CDS_SEC 1
J 0
(-4350 3950);
PAINT MONO (-4350 3950);
DISPLAY INVISIBLE (-4350 3950);
FORCEPROP 2 LAST CDS_LIB dev_discrete
J 0
(-4400 3750);
PAINT ORANGE (-4400 3750);
DISPLAY INVISIBLE (-4400 3750);
FORCEPROP 2 LAST BOM_COST PROC
J 0
(-4400 3750);
PAINT MONO (-4400 3750);
DISPLAY INVISIBLE (-4400 3750);
FORCEPROP 2 LAST CDS_LOCATION C2D38
J 0
(-4350 3850);
DISPLAY 0.617021 (-4350 3850);
PAINT AQUA (-4350 3850);
DISPLAY INVISIBLE (-4350 3850);
FORCEADD CAP_A..1
(-4500 3050);
FORCEPROP 1 LAST VALUE 22.0UF
J 0
(-4450 3150);
DISPLAY 0.617021 (-4450 3150);
PAINT SKYBLUE (-4450 3150);
FORCEPROP 1 LAST VOLTAGE 4V
J 0
(-4450 3100);
DISPLAY 0.617021 (-4450 3100);
PAINT SKYBLUE (-4450 3100);
FORCEPROP 1 LASTPIN (-4500 2950) $PN 2
J 0
(-4490 2930);
DISPLAY 0.617021 (-4490 2930);
PAINT ORANGE (-4490 2930);
FORCEPROP 1 LAST MATERIAL X6S
J 0
(-4450 3000);
DISPLAY 0.617021 (-4450 3000);
PAINT SKYBLUE (-4450 3000);
FORCEPROP 1 LAST PACK_TYPE 0603V
J 0
(-4450 2900);
DISPLAY 0.617021 (-4450 2900);
PAINT SKYBLUE (-4450 2900);
FORCEPROP 1 LASTPIN (-4500 3150) $PN 1
J 0
(-4490 3130);
DISPLAY 0.617021 (-4490 3130);
PAINT ORANGE (-4490 3130);
FORCEPROP 1 LAST PART_NUMBER E15431-004
J 0
(-4450 2950);
DISPLAY 0.617021 (-4450 2950);
PAINT BLUE (-4450 2950);
FORCEPROP 1 LAST TOLERANCE 20%
J 0
(-4450 3050);
DISPLAY 0.617021 (-4450 3050);
PAINT SKYBLUE (-4450 3050);
FORCEPROP 1 LAST LOCATION C2D35
J 0
(-4450 3200);
DISPLAY 0.617021 (-4450 3200);
PAINT AQUA (-4450 3200);
FORCEPROP 0 LAST GROUP PWR_MLCC_CAP
J 0
(-4444 2812);
DISPLAY 0.638298 (-4444 2812);
PAINT BROWN (-4444 2812);
DISPLAY BOTH (-4444 2812);
FORCEPROP 2 LAST CDS_LOCATION C2D35
J 0
(-4450 3150);
DISPLAY 0.617021 (-4450 3150);
PAINT AQUA (-4450 3150);
DISPLAY INVISIBLE (-4450 3150);
FORCEPROP 2 LAST BOM_COST PROC
J 0
(-4500 3050);
PAINT MONO (-4500 3050);
DISPLAY INVISIBLE (-4500 3050);
FORCEPROP 2 LAST CDS_LIB dev_discrete
J 0
(-4500 3050);
PAINT ORANGE (-4500 3050);
DISPLAY INVISIBLE (-4500 3050);
FORCEPROP 2 LAST CDS_SEC 1
J 0
(-4450 3250);
PAINT MONO (-4450 3250);
DISPLAY INVISIBLE (-4450 3250);
FORCEPROP 2 LAST $SEC 1
J 0
(-4450 3250);
PAINT MONO (-4450 3250);
DISPLAY INVISIBLE (-4450 3250);
FORCEPROP 1 LAST PATH I161
J 0
(-4450 3200);
DISPLAY 0.978723 (-4450 3200);
PAINT WHITE (-4450 3200);
DISPLAY INVISIBLE (-4450 3200);
FORCEPROP 2 LAST ROOM PVCCIN_CPU1_DECAP_VR
J 0
(-4450 3150);
PAINT ORANGE (-4450 3150);
DISPLAY INVISIBLE (-4450 3150);
FORCEADD VCC_CORE..1
(-4000 4725);
FORCEPROP 3 LASTPIN (-4000 4675) SIG_NAME PVCCMCP_CPU1\g
J 0
(-3990 4685);
DISPLAY 0.659574 (-3990 4685);
PAINT MONO (-3990 4685);
DISPLAY INVISIBLE (-3990 4685);
FORCEPROP 1 LAST HDL_POWER PVCCMCP_CPU1
J 1
(-4000 4775);
DISPLAY 0.617021 (-4000 4775);
PAINT GREEN (-4000 4775);
FORCEPROP 2 LAST CDS_LIB mstr_symbols
J 0
(-4000 4725);
PAINT ORANGE (-4000 4725);
DISPLAY INVISIBLE (-4000 4725);
FORCEPROP 1 LAST PATH I162
J 0
(-3950 4750);
DISPLAY 0.872340 (-3950 4750);
PAINT AQUA (-3950 4750);
DISPLAY INVISIBLE (-3950 4750);
FORCEADD VCC_CORE..1
(-4600 2475);
FORCEPROP 3 LASTPIN (-4600 2425) SIG_NAME PVCCMCP_CPU1\g
J 0
(-4590 2435);
DISPLAY 0.659574 (-4590 2435);
PAINT MONO (-4590 2435);
DISPLAY INVISIBLE (-4590 2435);
FORCEPROP 1 LAST HDL_POWER PVCCMCP_CPU1
J 1
(-4600 2525);
DISPLAY 0.617021 (-4600 2525);
PAINT GREEN (-4600 2525);
FORCEPROP 2 LAST CDS_LIB mstr_symbols
J 0
(-4600 2475);
PAINT ORANGE (-4600 2475);
DISPLAY INVISIBLE (-4600 2475);
FORCEPROP 1 LAST PATH I163
J 0
(-4550 2500);
DISPLAY 0.872340 (-4550 2500);
PAINT AQUA (-4550 2500);
DISPLAY INVISIBLE (-4550 2500);
FORCEADD CAP_A..1
(-4000 4450);
FORCEPROP 1 LAST PART_NUMBER E15431-004
J 0
(-3950 4300);
DISPLAY 0.617021 (-3950 4300);
PAINT BLUE (-3950 4300);
FORCEPROP 1 LAST TOLERANCE 20%
J 0
(-3950 4400);
DISPLAY 0.617021 (-3950 4400);
PAINT SKYBLUE (-3950 4400);
FORCEPROP 1 LAST MATERIAL X6S
J 0
(-3950 4350);
DISPLAY 0.617021 (-3950 4350);
PAINT SKYBLUE (-3950 4350);
FORCEPROP 1 LASTPIN (-4000 4350) $PN 2
J 0
(-3990 4330);
DISPLAY 0.617021 (-3990 4330);
PAINT ORANGE (-3990 4330);
FORCEPROP 1 LAST VOLTAGE 4V
J 0
(-3950 4450);
DISPLAY 0.617021 (-3950 4450);
PAINT SKYBLUE (-3950 4450);
FORCEPROP 1 LASTPIN (-4000 4550) $PN 1
J 0
(-3990 4530);
DISPLAY 0.617021 (-3990 4530);
PAINT ORANGE (-3990 4530);
FORCEPROP 1 LAST VALUE 22.0UF
J 0
(-3950 4500);
DISPLAY 0.617021 (-3950 4500);
PAINT SKYBLUE (-3950 4500);
FORCEPROP 1 LAST PACK_TYPE 0603V
J 0
(-3950 4250);
DISPLAY 0.617021 (-3950 4250);
PAINT SKYBLUE (-3950 4250);
FORCEPROP 1 LAST LOCATION C3D7
J 0
(-3950 4550);
DISPLAY 0.617021 (-3950 4550);
PAINT AQUA (-3950 4550);
FORCEPROP 0 LAST GROUP PWR_MCP_CAP
J 0
(-3950 4200);
DISPLAY 0.638298 (-3950 4200);
PAINT BROWN (-3950 4200);
DISPLAY BOTH (-3950 4200);
FORCEPROP 0 LAST ROOM PVCCIN_CPU1_DECAP_VR
J 0
(-3950 4650);
DISPLAY 1.021277 (-3950 4650);
PAINT ORANGE (-3950 4650);
DISPLAY INVISIBLE (-3950 4650);
FORCEPROP 1 LAST PATH I164
J 0
(-3950 4600);
DISPLAY 0.978723 (-3950 4600);
PAINT WHITE (-3950 4600);
DISPLAY INVISIBLE (-3950 4600);
FORCEPROP 2 LAST $SEC 1
J 0
(-3950 4650);
PAINT MONO (-3950 4650);
DISPLAY INVISIBLE (-3950 4650);
FORCEPROP 2 LAST CDS_SEC 1
J 0
(-3950 4650);
PAINT MONO (-3950 4650);
DISPLAY INVISIBLE (-3950 4650);
FORCEPROP 2 LAST CDS_LIB dev_discrete
J 0
(-4000 4450);
PAINT ORANGE (-4000 4450);
DISPLAY INVISIBLE (-4000 4450);
FORCEPROP 2 LAST CDS_LOCATION C3D7
J 0
(-3950 4550);
DISPLAY 0.617021 (-3950 4550);
PAINT AQUA (-3950 4550);
DISPLAY INVISIBLE (-3950 4550);
FORCEADD CAP_A..1
(-3750 4450);
FORCEPROP 1 LASTPIN (-3750 4350) $PN 2
J 0
(-3740 4330);
DISPLAY 0.617021 (-3740 4330);
PAINT ORANGE (-3740 4330);
FORCEPROP 1 LAST TOLERANCE 20%
J 0
(-3700 4400);
DISPLAY 0.617021 (-3700 4400);
PAINT SKYBLUE (-3700 4400);
FORCEPROP 1 LAST MATERIAL X6S
J 0
(-3700 4350);
DISPLAY 0.617021 (-3700 4350);
PAINT SKYBLUE (-3700 4350);
FORCEPROP 1 LAST VOLTAGE 4V
J 0
(-3700 4450);
DISPLAY 0.617021 (-3700 4450);
PAINT SKYBLUE (-3700 4450);
FORCEPROP 1 LAST VALUE 22.0UF
J 0
(-3700 4500);
DISPLAY 0.617021 (-3700 4500);
PAINT SKYBLUE (-3700 4500);
FORCEPROP 1 LAST LOCATION C2D39
J 0
(-3700 4550);
DISPLAY 0.617021 (-3700 4550);
PAINT AQUA (-3700 4550);
FORCEPROP 1 LASTPIN (-3750 4550) $PN 1
J 0
(-3740 4530);
DISPLAY 0.617021 (-3740 4530);
PAINT ORANGE (-3740 4530);
FORCEPROP 1 LAST PACK_TYPE 0603V
J 0
(-3700 4250);
DISPLAY 0.617021 (-3700 4250);
PAINT SKYBLUE (-3700 4250);
FORCEPROP 1 LAST PART_NUMBER E15431-004
J 0
(-3700 4300);
DISPLAY 0.617021 (-3700 4300);
PAINT BLUE (-3700 4300);
FORCEPROP 0 LAST GROUP PWR_MCP_CAP
J 0
(-3700 4150);
DISPLAY 0.638298 (-3700 4150);
PAINT BROWN (-3700 4150);
DISPLAY BOTH (-3700 4150);
FORCEPROP 2 LAST ROOM PVCCIN_CPU1_DECAP_VR
J 0
(-3700 4550);
PAINT ORANGE (-3700 4550);
DISPLAY INVISIBLE (-3700 4550);
FORCEPROP 1 LAST PATH I165
J 0
(-3700 4600);
DISPLAY 0.978723 (-3700 4600);
PAINT WHITE (-3700 4600);
DISPLAY INVISIBLE (-3700 4600);
FORCEPROP 2 LAST $SEC 1
J 0
(-3700 4650);
PAINT MONO (-3700 4650);
DISPLAY INVISIBLE (-3700 4650);
FORCEPROP 2 LAST CDS_SEC 1
J 0
(-3700 4650);
PAINT MONO (-3700 4650);
DISPLAY INVISIBLE (-3700 4650);
FORCEPROP 2 LAST CDS_LIB dev_discrete
J 0
(-3750 4450);
PAINT ORANGE (-3750 4450);
DISPLAY INVISIBLE (-3750 4450);
FORCEPROP 2 LAST BOM_COST PROC
J 0
(-3750 4450);
PAINT MONO (-3750 4450);
DISPLAY INVISIBLE (-3750 4450);
FORCEPROP 2 LAST CDS_LOCATION C2D39
J 0
(-3700 4550);
DISPLAY 0.617021 (-3700 4550);
PAINT AQUA (-3700 4550);
DISPLAY INVISIBLE (-3700 4550);
FORCEADD CAP_A..1
(-3500 4450);
FORCEPROP 1 LAST TOLERANCE 20%
J 0
(-3450 4400);
DISPLAY 0.617021 (-3450 4400);
PAINT SKYBLUE (-3450 4400);
FORCEPROP 1 LAST MATERIAL X6S
J 0
(-3450 4350);
DISPLAY 0.617021 (-3450 4350);
PAINT SKYBLUE (-3450 4350);
FORCEPROP 1 LAST VALUE 22.0UF
J 0
(-3450 4500);
DISPLAY 0.617021 (-3450 4500);
PAINT SKYBLUE (-3450 4500);
FORCEPROP 1 LAST PACK_TYPE 0603V
J 0
(-3450 4250);
DISPLAY 0.617021 (-3450 4250);
PAINT SKYBLUE (-3450 4250);
FORCEPROP 1 LAST LOCATION C3D17
J 0
(-3450 4550);
DISPLAY 0.617021 (-3450 4550);
PAINT AQUA (-3450 4550);
FORCEPROP 1 LASTPIN (-3500 4550) $PN 1
J 0
(-3490 4530);
DISPLAY 0.617021 (-3490 4530);
PAINT ORANGE (-3490 4530);
FORCEPROP 1 LAST VOLTAGE 4V
J 0
(-3450 4450);
DISPLAY 0.617021 (-3450 4450);
PAINT SKYBLUE (-3450 4450);
FORCEPROP 1 LAST PART_NUMBER E15431-004
J 0
(-3450 4300);
DISPLAY 0.617021 (-3450 4300);
PAINT BLUE (-3450 4300);
FORCEPROP 1 LASTPIN (-3500 4350) $PN 2
J 0
(-3490 4330);
DISPLAY 0.617021 (-3490 4330);
PAINT ORANGE (-3490 4330);
FORCEPROP 0 LAST GROUP PWR_MCP_CAP
J 0
(-3450 4200);
DISPLAY 0.638298 (-3450 4200);
PAINT BROWN (-3450 4200);
DISPLAY BOTH (-3450 4200);
FORCEPROP 2 LAST ROOM PVCCIN_CPU1_DECAP_VR
J 0
(-3450 4550);
PAINT ORANGE (-3450 4550);
DISPLAY INVISIBLE (-3450 4550);
FORCEPROP 1 LAST PATH I166
J 0
(-3450 4600);
DISPLAY 0.978723 (-3450 4600);
PAINT WHITE (-3450 4600);
DISPLAY INVISIBLE (-3450 4600);
FORCEPROP 2 LAST $SEC 1
J 0
(-3450 4650);
PAINT MONO (-3450 4650);
DISPLAY INVISIBLE (-3450 4650);
FORCEPROP 2 LAST CDS_SEC 1
J 0
(-3450 4650);
PAINT MONO (-3450 4650);
DISPLAY INVISIBLE (-3450 4650);
FORCEPROP 2 LAST CDS_LIB dev_discrete
J 0
(-3500 4450);
PAINT ORANGE (-3500 4450);
DISPLAY INVISIBLE (-3500 4450);
FORCEPROP 2 LAST BOM_COST PROC
J 0
(-3500 4450);
PAINT MONO (-3500 4450);
DISPLAY INVISIBLE (-3500 4450);
FORCEPROP 2 LAST CDS_LOCATION C3D17
J 0
(-3450 4550);
DISPLAY 0.617021 (-3450 4550);
PAINT AQUA (-3450 4550);
DISPLAY INVISIBLE (-3450 4550);
FORCEADD PVCCIO_CPU1..1
(-3850 4050);
FORCEPROP 3 LASTPIN (-3850 4000) SIG_NAME PVCCIO_CPU1\g
J 0
(-3840 4010);
DISPLAY 0.659574 (-3840 4010);
PAINT MONO (-3840 4010);
DISPLAY INVISIBLE (-3840 4010);
FORCEPROP 1 LAST VOLTAGE 1.1V
J 0
(-3895 4007);
DISPLAY 0.340426 (-3895 4007);
PAINT SKYBLUE (-3895 4007);
DISPLAY INVISIBLE (-3895 4007);
FORCEPROP 2 LAST CDS_LIB mstr_symbols
J 0
(-3850 4050);
PAINT ORANGE (-3850 4050);
DISPLAY INVISIBLE (-3850 4050);
FORCEPROP 1 LAST BODY_TYPE PLUMBING
J 0
(-3895 4007);
DISPLAY 0.340426 (-3895 4007);
PAINT GREEN (-3895 4007);
DISPLAY INVISIBLE (-3895 4007);
FORCEPROP 1 LAST PATH I167
J 0
(-3800 4075);
DISPLAY 0.872340 (-3800 4075);
PAINT AQUA (-3800 4075);
DISPLAY INVISIBLE (-3800 4075);
FORCEPROP 1 LAST HDL_POWER PVCCIO_CPU1
J 1
(-3850 4100);
DISPLAY 0.872340 (-3850 4100);
PAINT GREEN (-3850 4100);
DISPLAY INVISIBLE (-3850 4100);
FORCEADD CAP_A..1
(-975 4450);
FORCEPROP 0 LAST GROUP PWR_MCP_CAP
J 0
(-925 4150);
DISPLAY 0.638298 (-925 4150);
PAINT BROWN (-925 4150);
DISPLAY BOTH (-925 4150);
FORCEPROP 1 LAST TOLERANCE 20%
J 0
(-925 4400);
DISPLAY 0.617021 (-925 4400);
PAINT SKYBLUE (-925 4400);
FORCEPROP 1 LAST VOLTAGE 4V
J 0
(-925 4450);
DISPLAY 0.617021 (-925 4450);
PAINT SKYBLUE (-925 4450);
FORCEPROP 1 LAST PACK_TYPE 0603V
J 0
(-925 4250);
DISPLAY 0.617021 (-925 4250);
PAINT SKYBLUE (-925 4250);
FORCEPROP 1 LAST PART_NUMBER E15431-004
J 0
(-925 4300);
DISPLAY 0.617021 (-925 4300);
PAINT BLUE (-925 4300);
FORCEPROP 1 LASTPIN (-975 4350) $PN 2
J 0
(-965 4330);
DISPLAY 0.617021 (-965 4330);
PAINT ORANGE (-965 4330);
FORCEPROP 1 LASTPIN (-975 4550) $PN 1
J 0
(-965 4530);
DISPLAY 0.617021 (-965 4530);
PAINT ORANGE (-965 4530);
FORCEPROP 1 LAST MATERIAL X6S
J 0
(-925 4350);
DISPLAY 0.617021 (-925 4350);
PAINT SKYBLUE (-925 4350);
FORCEPROP 1 LAST VALUE 22.0UF
J 0
(-925 4500);
DISPLAY 0.617021 (-925 4500);
PAINT SKYBLUE (-925 4500);
FORCEPROP 1 LAST LOCATION C3D18
J 0
(-925 4550);
DISPLAY 0.617021 (-925 4550);
PAINT AQUA (-925 4550);
FORCEPROP 2 LAST ROOM PVCCIN_CPU1_DECAP_VR
J 0
(-925 4550);
PAINT ORANGE (-925 4550);
DISPLAY INVISIBLE (-925 4550);
FORCEPROP 1 LAST PATH I169
J 0
(-925 4600);
DISPLAY 0.978723 (-925 4600);
PAINT WHITE (-925 4600);
DISPLAY INVISIBLE (-925 4600);
FORCEPROP 2 LAST $SEC 1
J 0
(-925 4650);
PAINT MONO (-925 4650);
DISPLAY INVISIBLE (-925 4650);
FORCEPROP 2 LAST CDS_SEC 1
J 0
(-925 4650);
PAINT MONO (-925 4650);
DISPLAY INVISIBLE (-925 4650);
FORCEPROP 2 LAST CDS_LIB dev_discrete
J 0
(-975 4450);
PAINT ORANGE (-975 4450);
DISPLAY INVISIBLE (-975 4450);
FORCEPROP 2 LAST BOM_COST PROC
J 0
(-975 4450);
PAINT MONO (-975 4450);
DISPLAY INVISIBLE (-975 4450);
FORCEPROP 2 LAST CDS_LOCATION C3D18
J 0
(-925 4550);
DISPLAY 0.617021 (-925 4550);
PAINT AQUA (-925 4550);
DISPLAY INVISIBLE (-925 4550);
FORCEADD CAP_A..1
(-725 4450);
FORCEPROP 0 LAST GROUP PWR_MCP_CAP
J 0
(-675 4200);
DISPLAY 0.638298 (-675 4200);
PAINT BROWN (-675 4200);
DISPLAY BOTH (-675 4200);
FORCEPROP 1 LAST PACK_TYPE 0603V
J 0
(-675 4250);
DISPLAY 0.617021 (-675 4250);
PAINT SKYBLUE (-675 4250);
FORCEPROP 1 LAST PART_NUMBER E15431-004
J 0
(-675 4300);
DISPLAY 0.617021 (-675 4300);
PAINT BLUE (-675 4300);
FORCEPROP 1 LAST MATERIAL X6S
J 0
(-675 4350);
DISPLAY 0.617021 (-675 4350);
PAINT SKYBLUE (-675 4350);
FORCEPROP 1 LAST TOLERANCE 20%
J 0
(-675 4400);
DISPLAY 0.617021 (-675 4400);
PAINT SKYBLUE (-675 4400);
FORCEPROP 1 LAST VOLTAGE 4V
J 0
(-675 4450);
DISPLAY 0.617021 (-675 4450);
PAINT SKYBLUE (-675 4450);
FORCEPROP 1 LASTPIN (-725 4350) $PN 2
J 0
(-715 4330);
DISPLAY 0.617021 (-715 4330);
PAINT ORANGE (-715 4330);
FORCEPROP 1 LASTPIN (-725 4550) $PN 1
J 0
(-715 4530);
DISPLAY 0.617021 (-715 4530);
PAINT ORANGE (-715 4530);
FORCEPROP 1 LAST VALUE 22.0UF
J 0
(-675 4500);
DISPLAY 0.617021 (-675 4500);
PAINT SKYBLUE (-675 4500);
FORCEPROP 1 LAST LOCATION C3D6
J 0
(-675 4550);
DISPLAY 0.617021 (-675 4550);
PAINT AQUA (-675 4550);
FORCEPROP 2 LAST ROOM PVCCIN_CPU1_DECAP_VR
J 0
(-675 4550);
PAINT ORANGE (-675 4550);
DISPLAY INVISIBLE (-675 4550);
FORCEPROP 1 LAST PATH I170
J 0
(-675 4600);
DISPLAY 0.978723 (-675 4600);
PAINT WHITE (-675 4600);
DISPLAY INVISIBLE (-675 4600);
FORCEPROP 2 LAST $SEC 1
J 0
(-675 4650);
PAINT MONO (-675 4650);
DISPLAY INVISIBLE (-675 4650);
FORCEPROP 2 LAST CDS_SEC 1
J 0
(-675 4650);
PAINT MONO (-675 4650);
DISPLAY INVISIBLE (-675 4650);
FORCEPROP 2 LAST CDS_LIB dev_discrete
J 0
(-725 4450);
PAINT ORANGE (-725 4450);
DISPLAY INVISIBLE (-725 4450);
FORCEPROP 2 LAST BOM_COST PROC
J 0
(-725 4450);
PAINT MONO (-725 4450);
DISPLAY INVISIBLE (-725 4450);
FORCEPROP 2 LAST CDS_LOCATION C3D6
J 0
(-675 4550);
DISPLAY 0.617021 (-675 4550);
PAINT AQUA (-675 4550);
DISPLAY INVISIBLE (-675 4550);
FORCEADD CAP_A..1
(-2725 4450);
FORCEPROP 1 LAST MATERIAL X6S
J 0
(-2675 4350);
DISPLAY 0.617021 (-2675 4350);
PAINT SKYBLUE (-2675 4350);
FORCEPROP 1 LAST TOLERANCE 20%
J 0
(-2675 4400);
DISPLAY 0.617021 (-2675 4400);
PAINT SKYBLUE (-2675 4400);
FORCEPROP 1 LASTPIN (-2725 4350) $PN 2
J 0
(-2715 4330);
DISPLAY 0.617021 (-2715 4330);
PAINT ORANGE (-2715 4330);
FORCEPROP 1 LASTPIN (-2725 4550) $PN 1
J 0
(-2715 4530);
DISPLAY 0.617021 (-2715 4530);
PAINT ORANGE (-2715 4530);
FORCEPROP 1 LAST VOLTAGE 4V
J 0
(-2675 4450);
DISPLAY 0.617021 (-2675 4450);
PAINT SKYBLUE (-2675 4450);
FORCEPROP 1 LAST LOCATION C3D14
J 0
(-2675 4550);
DISPLAY 0.617021 (-2675 4550);
PAINT AQUA (-2675 4550);
FORCEPROP 1 LAST VALUE 22.0UF
J 0
(-2675 4500);
DISPLAY 0.617021 (-2675 4500);
PAINT SKYBLUE (-2675 4500);
FORCEPROP 1 LAST PACK_TYPE 0603V
J 0
(-2675 4250);
DISPLAY 0.617021 (-2675 4250);
PAINT SKYBLUE (-2675 4250);
FORCEPROP 1 LAST PART_NUMBER E15431-004
J 0
(-2675 4300);
DISPLAY 0.617021 (-2675 4300);
PAINT BLUE (-2675 4300);
FORCEPROP 0 LAST GROUP PWR_MCP_CAP
J 0
(-2675 4150);
DISPLAY 0.638298 (-2675 4150);
PAINT BROWN (-2675 4150);
DISPLAY BOTH (-2675 4150);
FORCEPROP 2 LAST ROOM PVCCIN_CPU1_DECAP_VR
J 0
(-2675 4550);
PAINT ORANGE (-2675 4550);
DISPLAY INVISIBLE (-2675 4550);
FORCEPROP 1 LAST PATH I171
J 0
(-2675 4600);
DISPLAY 0.978723 (-2675 4600);
PAINT WHITE (-2675 4600);
DISPLAY INVISIBLE (-2675 4600);
FORCEPROP 2 LAST $SEC 1
J 0
(-2675 4650);
PAINT MONO (-2675 4650);
DISPLAY INVISIBLE (-2675 4650);
FORCEPROP 2 LAST CDS_SEC 1
J 0
(-2675 4650);
PAINT MONO (-2675 4650);
DISPLAY INVISIBLE (-2675 4650);
FORCEPROP 2 LAST CDS_LIB dev_discrete
J 0
(-2725 4450);
PAINT ORANGE (-2725 4450);
DISPLAY INVISIBLE (-2725 4450);
FORCEPROP 2 LAST BOM_COST PROC
J 0
(-2725 4450);
PAINT MONO (-2725 4450);
DISPLAY INVISIBLE (-2725 4450);
FORCEPROP 2 LAST CDS_LOCATION C3D14
J 0
(-2675 4550);
DISPLAY 0.617021 (-2675 4550);
PAINT AQUA (-2675 4550);
DISPLAY INVISIBLE (-2675 4550);
FORCEADD CAP_A..1
(-3850 3750);
FORCEPROP 1 LAST VALUE 22.0UF
J 0
(-3800 3850);
DISPLAY 0.617021 (-3800 3850);
PAINT SKYBLUE (-3800 3850);
FORCEPROP 1 LASTPIN (-3850 3850) $PN 1
J 0
(-3840 3830);
DISPLAY 0.617021 (-3840 3830);
PAINT ORANGE (-3840 3830);
FORCEPROP 1 LASTPIN (-3850 3650) $PN 2
J 0
(-3840 3630);
DISPLAY 0.617021 (-3840 3630);
PAINT ORANGE (-3840 3630);
FORCEPROP 1 LAST VOLTAGE 4V
J 0
(-3800 3800);
DISPLAY 0.617021 (-3800 3800);
PAINT SKYBLUE (-3800 3800);
FORCEPROP 1 LAST TOLERANCE 20%
J 0
(-3800 3750);
DISPLAY 0.617021 (-3800 3750);
PAINT SKYBLUE (-3800 3750);
FORCEPROP 1 LAST PACK_TYPE 0603V
J 0
(-3800 3600);
DISPLAY 0.617021 (-3800 3600);
PAINT SKYBLUE (-3800 3600);
FORCEPROP 1 LAST PART_NUMBER E15431-004
J 0
(-3800 3650);
DISPLAY 0.617021 (-3800 3650);
PAINT BLUE (-3800 3650);
FORCEPROP 1 LAST MATERIAL X6S
J 0
(-3800 3700);
DISPLAY 0.617021 (-3800 3700);
PAINT SKYBLUE (-3800 3700);
FORCEPROP 1 LAST LOCATION C3D23
J 0
(-3800 3900);
DISPLAY 0.617021 (-3800 3900);
PAINT AQUA (-3800 3900);
FORCEPROP 0 LAST GROUP PWR_MLCC_CAP
J 0
(-3794 3562);
DISPLAY 0.638298 (-3794 3562);
PAINT BROWN (-3794 3562);
DISPLAY BOTH (-3794 3562);
FORCEPROP 2 LAST CDS_LOCATION C3D23
J 0
(-3800 3850);
DISPLAY 0.617021 (-3800 3850);
PAINT AQUA (-3800 3850);
DISPLAY INVISIBLE (-3800 3850);
FORCEPROP 2 LAST BOM_COST PROC
J 0
(-3850 3750);
PAINT MONO (-3850 3750);
DISPLAY INVISIBLE (-3850 3750);
FORCEPROP 2 LAST CDS_LIB dev_discrete
J 0
(-3850 3750);
PAINT ORANGE (-3850 3750);
DISPLAY INVISIBLE (-3850 3750);
FORCEPROP 2 LAST CDS_SEC 1
J 0
(-3800 3950);
PAINT MONO (-3800 3950);
DISPLAY INVISIBLE (-3800 3950);
FORCEPROP 2 LAST $SEC 1
J 0
(-3800 3950);
PAINT MONO (-3800 3950);
DISPLAY INVISIBLE (-3800 3950);
FORCEPROP 1 LAST PATH I172
J 0
(-3800 3900);
DISPLAY 0.978723 (-3800 3900);
PAINT WHITE (-3800 3900);
DISPLAY INVISIBLE (-3800 3900);
FORCEPROP 2 LAST ROOM PVCCIN_CPU1_DECAP_VR
J 0
(-3800 3850);
PAINT ORANGE (-3800 3850);
DISPLAY INVISIBLE (-3800 3850);
FORCEADD CAP_A..1
(-3550 3750);
FORCEPROP 1 LAST PART_NUMBER E15431-004
J 0
(-3500 3650);
DISPLAY 0.617021 (-3500 3650);
PAINT BLUE (-3500 3650);
FORCEPROP 1 LAST PACK_TYPE 0603V
J 0
(-3500 3600);
DISPLAY 0.617021 (-3500 3600);
PAINT SKYBLUE (-3500 3600);
FORCEPROP 1 LAST MATERIAL X6S
J 0
(-3500 3700);
DISPLAY 0.617021 (-3500 3700);
PAINT SKYBLUE (-3500 3700);
FORCEPROP 1 LASTPIN (-3550 3650) $PN 2
J 0
(-3540 3630);
DISPLAY 0.617021 (-3540 3630);
PAINT ORANGE (-3540 3630);
FORCEPROP 1 LAST VOLTAGE 4V
J 0
(-3500 3800);
DISPLAY 0.617021 (-3500 3800);
PAINT SKYBLUE (-3500 3800);
FORCEPROP 1 LASTPIN (-3550 3850) $PN 1
J 0
(-3540 3830);
DISPLAY 0.617021 (-3540 3830);
PAINT ORANGE (-3540 3830);
FORCEPROP 1 LAST TOLERANCE 20%
J 0
(-3500 3750);
DISPLAY 0.617021 (-3500 3750);
PAINT SKYBLUE (-3500 3750);
FORCEPROP 0 LAST GROUP PWR_MLCC_CAP
J 0
(-3494 3512);
DISPLAY 0.638298 (-3494 3512);
PAINT BROWN (-3494 3512);
DISPLAY BOTH (-3494 3512);
FORCEPROP 1 LAST VALUE 22.0UF
J 0
(-3500 3850);
DISPLAY 0.617021 (-3500 3850);
PAINT SKYBLUE (-3500 3850);
FORCEPROP 1 LAST LOCATION C3D15
J 0
(-3500 3900);
DISPLAY 0.617021 (-3500 3900);
PAINT AQUA (-3500 3900);
FORCEPROP 2 LAST ROOM PVCCIN_CPU1_DECAP_VR
J 0
(-3500 3850);
PAINT ORANGE (-3500 3850);
DISPLAY INVISIBLE (-3500 3850);
FORCEPROP 1 LAST PATH I174
J 0
(-3500 3900);
DISPLAY 0.978723 (-3500 3900);
PAINT WHITE (-3500 3900);
DISPLAY INVISIBLE (-3500 3900);
FORCEPROP 2 LAST $SEC 1
J 0
(-3500 3950);
PAINT MONO (-3500 3950);
DISPLAY INVISIBLE (-3500 3950);
FORCEPROP 2 LAST CDS_SEC 1
J 0
(-3500 3950);
PAINT MONO (-3500 3950);
DISPLAY INVISIBLE (-3500 3950);
FORCEPROP 2 LAST CDS_LIB dev_discrete
J 0
(-3550 3750);
PAINT ORANGE (-3550 3750);
DISPLAY INVISIBLE (-3550 3750);
FORCEPROP 2 LAST BOM_COST PROC
J 0
(-3550 3750);
PAINT MONO (-3550 3750);
DISPLAY INVISIBLE (-3550 3750);
FORCEPROP 2 LAST CDS_LOCATION C3D15
J 0
(-3500 3850);
DISPLAY 0.617021 (-3500 3850);
PAINT AQUA (-3500 3850);
DISPLAY INVISIBLE (-3500 3850);
FORCEADD CAP_A..1
(-3250 3750);
FORCEPROP 1 LAST PART_NUMBER E15431-004
J 0
(-3200 3650);
DISPLAY 0.617021 (-3200 3650);
PAINT BLUE (-3200 3650);
FORCEPROP 1 LAST PACK_TYPE 0603V
J 0
(-3200 3600);
DISPLAY 0.617021 (-3200 3600);
PAINT SKYBLUE (-3200 3600);
FORCEPROP 1 LAST MATERIAL X6S
J 0
(-3200 3700);
DISPLAY 0.617021 (-3200 3700);
PAINT SKYBLUE (-3200 3700);
FORCEPROP 0 LAST GROUP PWR_MLCC_CAP
J 0
(-3194 3562);
DISPLAY 0.638298 (-3194 3562);
PAINT BROWN (-3194 3562);
DISPLAY BOTH (-3194 3562);
FORCEPROP 1 LAST TOLERANCE 20%
J 0
(-3200 3750);
DISPLAY 0.617021 (-3200 3750);
PAINT SKYBLUE (-3200 3750);
FORCEPROP 1 LASTPIN (-3250 3650) $PN 2
J 0
(-3240 3630);
DISPLAY 0.617021 (-3240 3630);
PAINT ORANGE (-3240 3630);
FORCEPROP 1 LAST LOCATION C3D24
J 0
(-3200 3900);
DISPLAY 0.617021 (-3200 3900);
PAINT AQUA (-3200 3900);
FORCEPROP 1 LAST VALUE 22.0UF
J 0
(-3200 3850);
DISPLAY 0.617021 (-3200 3850);
PAINT SKYBLUE (-3200 3850);
FORCEPROP 1 LAST VOLTAGE 4V
J 0
(-3200 3800);
DISPLAY 0.617021 (-3200 3800);
PAINT SKYBLUE (-3200 3800);
FORCEPROP 1 LASTPIN (-3250 3850) $PN 1
J 0
(-3240 3830);
DISPLAY 0.617021 (-3240 3830);
PAINT ORANGE (-3240 3830);
FORCEPROP 2 LAST CDS_LOCATION C3D24
J 0
(-3200 3850);
DISPLAY 0.617021 (-3200 3850);
PAINT AQUA (-3200 3850);
DISPLAY INVISIBLE (-3200 3850);
FORCEPROP 2 LAST BOM_COST PROC
J 0
(-3250 3750);
PAINT MONO (-3250 3750);
DISPLAY INVISIBLE (-3250 3750);
FORCEPROP 2 LAST CDS_LIB dev_discrete
J 0
(-3250 3750);
PAINT ORANGE (-3250 3750);
DISPLAY INVISIBLE (-3250 3750);
FORCEPROP 2 LAST CDS_SEC 1
J 0
(-3200 3950);
PAINT MONO (-3200 3950);
DISPLAY INVISIBLE (-3200 3950);
FORCEPROP 2 LAST $SEC 1
J 0
(-3200 3950);
PAINT MONO (-3200 3950);
DISPLAY INVISIBLE (-3200 3950);
FORCEPROP 1 LAST PATH I175
J 0
(-3200 3900);
DISPLAY 0.978723 (-3200 3900);
PAINT WHITE (-3200 3900);
DISPLAY INVISIBLE (-3200 3900);
FORCEPROP 2 LAST ROOM PVCCIN_CPU1_DECAP_VR
J 0
(-3200 3850);
PAINT ORANGE (-3200 3850);
DISPLAY INVISIBLE (-3200 3850);
FORCEADD CAP_A..1
(-2950 3750);
FORCEPROP 1 LAST PACK_TYPE 0603V
J 0
(-2900 3600);
DISPLAY 0.617021 (-2900 3600);
PAINT SKYBLUE (-2900 3600);
FORCEPROP 1 LAST MATERIAL X6S
J 0
(-2900 3700);
DISPLAY 0.617021 (-2900 3700);
PAINT SKYBLUE (-2900 3700);
FORCEPROP 1 LAST PART_NUMBER E15431-004
J 0
(-2900 3650);
DISPLAY 0.617021 (-2900 3650);
PAINT BLUE (-2900 3650);
FORCEPROP 1 LAST LOCATION C3D16
J 0
(-2900 3900);
DISPLAY 0.617021 (-2900 3900);
PAINT AQUA (-2900 3900);
FORCEPROP 1 LAST VALUE 22.0UF
J 0
(-2900 3850);
DISPLAY 0.617021 (-2900 3850);
PAINT SKYBLUE (-2900 3850);
FORCEPROP 0 LAST GROUP PWR_MLCC_CAP
J 0
(-2894 3512);
DISPLAY 0.638298 (-2894 3512);
PAINT BROWN (-2894 3512);
DISPLAY BOTH (-2894 3512);
FORCEPROP 1 LASTPIN (-2950 3650) $PN 2
J 0
(-2940 3630);
DISPLAY 0.617021 (-2940 3630);
PAINT ORANGE (-2940 3630);
FORCEPROP 1 LAST TOLERANCE 20%
J 0
(-2900 3750);
DISPLAY 0.617021 (-2900 3750);
PAINT SKYBLUE (-2900 3750);
FORCEPROP 1 LAST VOLTAGE 4V
J 0
(-2900 3800);
DISPLAY 0.617021 (-2900 3800);
PAINT SKYBLUE (-2900 3800);
FORCEPROP 1 LASTPIN (-2950 3850) $PN 1
J 0
(-2940 3830);
DISPLAY 0.617021 (-2940 3830);
PAINT ORANGE (-2940 3830);
FORCEPROP 2 LAST CDS_LOCATION C3D16
J 0
(-2900 3850);
DISPLAY 0.617021 (-2900 3850);
PAINT AQUA (-2900 3850);
DISPLAY INVISIBLE (-2900 3850);
FORCEPROP 2 LAST BOM_COST PROC
J 0
(-2950 3750);
PAINT MONO (-2950 3750);
DISPLAY INVISIBLE (-2950 3750);
FORCEPROP 2 LAST CDS_LIB dev_discrete
J 0
(-2950 3750);
PAINT ORANGE (-2950 3750);
DISPLAY INVISIBLE (-2950 3750);
FORCEPROP 2 LAST CDS_SEC 1
J 0
(-2900 3950);
PAINT MONO (-2900 3950);
DISPLAY INVISIBLE (-2900 3950);
FORCEPROP 2 LAST $SEC 1
J 0
(-2900 3950);
PAINT MONO (-2900 3950);
DISPLAY INVISIBLE (-2900 3950);
FORCEPROP 1 LAST PATH I176
J 0
(-2900 3900);
DISPLAY 0.978723 (-2900 3900);
PAINT WHITE (-2900 3900);
DISPLAY INVISIBLE (-2900 3900);
FORCEPROP 2 LAST ROOM PVCCIN_CPU1_DECAP_VR
J 0
(-2900 3850);
PAINT ORANGE (-2900 3850);
DISPLAY INVISIBLE (-2900 3850);
FORCEADD CAP_A..1
(-2400 1150);
FORCEPROP 1 LAST LOCATION C7P12
J 0
(-2350 1300);
DISPLAY 0.617021 (-2350 1300);
PAINT AQUA (-2350 1300);
FORCEPROP 1 LAST VALUE 22.0UF
J 0
(-2350 1250);
DISPLAY 0.617021 (-2350 1250);
PAINT SKYBLUE (-2350 1250);
FORCEPROP 1 LAST VOLTAGE 4V
J 0
(-2350 1200);
DISPLAY 0.617021 (-2350 1200);
PAINT SKYBLUE (-2350 1200);
FORCEPROP 1 LAST TOLERANCE 20%
J 0
(-2350 1150);
DISPLAY 0.617021 (-2350 1150);
PAINT SKYBLUE (-2350 1150);
FORCEPROP 1 LAST MATERIAL X6S
J 0
(-2350 1100);
DISPLAY 0.617021 (-2350 1100);
PAINT SKYBLUE (-2350 1100);
FORCEPROP 1 LAST PART_NUMBER E15431-004
J 0
(-2350 1050);
DISPLAY 0.617021 (-2350 1050);
PAINT BLUE (-2350 1050);
FORCEPROP 1 LAST PACK_TYPE 0603V
J 0
(-2350 1000);
DISPLAY 0.617021 (-2350 1000);
PAINT SKYBLUE (-2350 1000);
FORCEPROP 0 LAST GROUP PWR_MLCC_CAP
J 0
(-2344 887);
DISPLAY 0.638298 (-2344 887);
PAINT BROWN (-2344 887);
DISPLAY BOTH (-2344 887);
FORCEPROP 1 LASTPIN (-2400 1050) $PN 2
J 0
(-2390 1030);
DISPLAY 0.617021 (-2390 1030);
PAINT ORANGE (-2390 1030);
FORCEPROP 1 LASTPIN (-2400 1250) $PN 1
J 0
(-2390 1230);
DISPLAY 0.617021 (-2390 1230);
PAINT ORANGE (-2390 1230);
FORCEPROP 2 LAST ROOM PVCCIN_CPU1_DECAP_VR
J 0
(-2350 1250);
PAINT ORANGE (-2350 1250);
DISPLAY INVISIBLE (-2350 1250);
FORCEPROP 1 LAST PATH I179
J 0
(-2350 1300);
DISPLAY 0.978723 (-2350 1300);
PAINT WHITE (-2350 1300);
DISPLAY INVISIBLE (-2350 1300);
FORCEPROP 2 LAST $SEC 1
J 0
(-2350 1350);
PAINT MONO (-2350 1350);
DISPLAY INVISIBLE (-2350 1350);
FORCEPROP 2 LAST CDS_SEC 1
J 0
(-2350 1350);
PAINT MONO (-2350 1350);
DISPLAY INVISIBLE (-2350 1350);
FORCEPROP 2 LAST CDS_LIB dev_discrete
J 0
(-2400 1150);
PAINT ORANGE (-2400 1150);
DISPLAY INVISIBLE (-2400 1150);
FORCEPROP 2 LAST BOM_COST PROC
J 0
(-2400 1150);
PAINT MONO (-2400 1150);
DISPLAY INVISIBLE (-2400 1150);
FORCEPROP 2 LAST CDS_LOCATION C7P12
J 0
(-2350 1250);
DISPLAY 0.617021 (-2350 1250);
PAINT AQUA (-2350 1250);
DISPLAY INVISIBLE (-2350 1250);
FORCEADD CAP_A..1
(-2650 3750);
FORCEPROP 1 LAST PART_NUMBER E15431-004
J 0
(-2600 3650);
DISPLAY 0.617021 (-2600 3650);
PAINT BLUE (-2600 3650);
FORCEPROP 1 LAST PACK_TYPE 0603V
J 0
(-2600 3600);
DISPLAY 0.617021 (-2600 3600);
PAINT SKYBLUE (-2600 3600);
FORCEPROP 1 LAST VALUE 22.0UF
J 0
(-2600 3850);
DISPLAY 0.617021 (-2600 3850);
PAINT SKYBLUE (-2600 3850);
FORCEPROP 1 LASTPIN (-2650 3850) $PN 1
J 0
(-2640 3830);
DISPLAY 0.617021 (-2640 3830);
PAINT GREEN (-2640 3830);
FORCEPROP 1 LAST LOCATION C3D8
J 0
(-2600 3900);
DISPLAY 0.617021 (-2600 3900);
PAINT AQUA (-2600 3900);
FORCEPROP 1 LASTPIN (-2650 3650) $PN 2
J 0
(-2640 3630);
DISPLAY 0.617021 (-2640 3630);
PAINT GREEN (-2640 3630);
FORCEPROP 1 LAST MATERIAL X6S
J 0
(-2600 3700);
DISPLAY 0.617021 (-2600 3700);
PAINT SKYBLUE (-2600 3700);
FORCEPROP 0 LAST GROUP PWR_MLCC_CAP
J 0
(-2594 3562);
DISPLAY 0.638298 (-2594 3562);
PAINT BROWN (-2594 3562);
DISPLAY BOTH (-2594 3562);
FORCEPROP 1 LAST TOLERANCE 20%
J 0
(-2600 3750);
DISPLAY 0.617021 (-2600 3750);
PAINT SKYBLUE (-2600 3750);
FORCEPROP 1 LAST VOLTAGE 4V
J 0
(-2600 3800);
DISPLAY 0.617021 (-2600 3800);
PAINT SKYBLUE (-2600 3800);
FORCEPROP 2 LAST CDS_LOCATION C3D8
J 0
(-2600 3850);
DISPLAY 0.617021 (-2600 3850);
PAINT AQUA (-2600 3850);
DISPLAY INVISIBLE (-2600 3850);
FORCEPROP 2 LAST BOM_COST PROC
J 0
(-2650 3750);
PAINT MONO (-2650 3750);
DISPLAY INVISIBLE (-2650 3750);
FORCEPROP 2 LAST CDS_LIB dev_discrete
J 0
(-2650 3750);
PAINT ORANGE (-2650 3750);
DISPLAY INVISIBLE (-2650 3750);
FORCEPROP 2 LAST CDS_SEC 1
J 0
(-2600 3950);
PAINT MONO (-2600 3950);
DISPLAY INVISIBLE (-2600 3950);
FORCEPROP 2 LAST $SEC 1
J 0
(-2600 3950);
PAINT MONO (-2600 3950);
DISPLAY INVISIBLE (-2600 3950);
FORCEPROP 1 LAST PATH I18
J 0
(-2600 3900);
DISPLAY 0.978723 (-2600 3900);
PAINT WHITE (-2600 3900);
DISPLAY INVISIBLE (-2600 3900);
FORCEPROP 2 LAST ROOM PVCCIN_CPU1_DECAP_VR
J 0
(-2600 3850);
PAINT ORANGE (-2600 3850);
DISPLAY INVISIBLE (-2600 3850);
FORCEADD CAP_A..1
(-1975 3775);
FORCEPROP 1 LAST TOLERANCE 20%
J 0
(-1925 3725);
DISPLAY 0.617021 (-1925 3725);
PAINT SKYBLUE (-1925 3725);
FORCEPROP 1 LAST LOCATION C3D10
J 0
(-1925 3875);
DISPLAY 0.617021 (-1925 3875);
PAINT AQUA (-1925 3875);
FORCEPROP 0 LAST GROUP PWR_MCP_CAP
J 0
(-1925 3475);
DISPLAY 0.638298 (-1925 3475);
PAINT BROWN (-1925 3475);
DISPLAY BOTH (-1925 3475);
FORCEPROP 1 LAST MATERIAL X6S
J 0
(-1925 3675);
DISPLAY 0.617021 (-1925 3675);
PAINT SKYBLUE (-1925 3675);
FORCEPROP 1 LAST VOLTAGE 4V
J 0
(-1925 3775);
DISPLAY 0.617021 (-1925 3775);
PAINT SKYBLUE (-1925 3775);
FORCEPROP 1 LAST VALUE 22.0UF
J 0
(-1925 3825);
DISPLAY 0.617021 (-1925 3825);
PAINT SKYBLUE (-1925 3825);
FORCEPROP 1 LAST PART_NUMBER E15431-004
J 0
(-1925 3625);
DISPLAY 0.617021 (-1925 3625);
PAINT BLUE (-1925 3625);
FORCEPROP 1 LAST PACK_TYPE 0603V
J 0
(-1925 3575);
DISPLAY 0.617021 (-1925 3575);
PAINT SKYBLUE (-1925 3575);
FORCEPROP 2 LAST CDS_LOCATION C3D10
J 0
(-1925 3875);
DISPLAY 0.617021 (-1925 3875);
PAINT AQUA (-1925 3875);
DISPLAY INVISIBLE (-1925 3875);
FORCEPROP 2 LAST BOM_COST PROC
J 0
(-1975 3775);
PAINT MONO (-1975 3775);
DISPLAY INVISIBLE (-1975 3775);
FORCEPROP 2 LAST CDS_LIB dev_discrete
J 0
(-1975 3775);
PAINT ORANGE (-1975 3775);
DISPLAY INVISIBLE (-1975 3775);
FORCEPROP 2 LAST CDS_SEC 1
J 0
(-1925 3975);
PAINT MONO (-1925 3975);
DISPLAY INVISIBLE (-1925 3975);
FORCEPROP 2 LAST $SEC 1
J 0
(-1925 3975);
PAINT MONO (-1925 3975);
DISPLAY INVISIBLE (-1925 3975);
FORCEPROP 1 LAST PATH I196
J 0
(-1925 3925);
DISPLAY 0.978723 (-1925 3925);
PAINT WHITE (-1925 3925);
DISPLAY INVISIBLE (-1925 3925);
FORCEPROP 2 LAST ROOM PVCCIN_CPU1_DECAP_VR
J 0
(-1925 3875);
PAINT ORANGE (-1925 3875);
DISPLAY INVISIBLE (-1925 3875);
FORCEPROP 1 LASTPIN (-1975 3875) $PN 1
J 0
(-1965 3855);
DISPLAY 0.787234 (-1965 3855);
PAINT ORANGE (-1965 3855);
DISPLAY INVISIBLE (-1965 3855);
FORCEPROP 1 LASTPIN (-1975 3675) $PN 2
J 0
(-1965 3655);
DISPLAY 0.787234 (-1965 3655);
PAINT ORANGE (-1965 3655);
DISPLAY INVISIBLE (-1965 3655);
FORCEADD CAP_A..1
(-1725 3775);
FORCEPROP 1 LAST TOLERANCE 20%
J 0
(-1675 3725);
DISPLAY 0.617021 (-1675 3725);
PAINT SKYBLUE (-1675 3725);
FORCEPROP 1 LAST VOLTAGE 4V
J 0
(-1675 3775);
DISPLAY 0.617021 (-1675 3775);
PAINT SKYBLUE (-1675 3775);
FORCEPROP 1 LAST VALUE 22.0UF
J 0
(-1675 3825);
DISPLAY 0.617021 (-1675 3825);
PAINT SKYBLUE (-1675 3825);
FORCEPROP 0 LAST GROUP PWR_MCP_CAP
J 0
(-1675 3525);
DISPLAY 0.638298 (-1675 3525);
PAINT BROWN (-1675 3525);
DISPLAY BOTH (-1675 3525);
FORCEPROP 1 LAST PART_NUMBER E15431-004
J 0
(-1675 3625);
DISPLAY 0.617021 (-1675 3625);
PAINT BLUE (-1675 3625);
FORCEPROP 1 LAST MATERIAL X6S
J 0
(-1675 3675);
DISPLAY 0.617021 (-1675 3675);
PAINT SKYBLUE (-1675 3675);
FORCEPROP 1 LAST LOCATION C2D18
J 0
(-1675 3875);
DISPLAY 0.617021 (-1675 3875);
PAINT AQUA (-1675 3875);
FORCEPROP 1 LAST PACK_TYPE 0603V
J 0
(-1675 3575);
DISPLAY 0.617021 (-1675 3575);
PAINT SKYBLUE (-1675 3575);
FORCEPROP 2 LAST CDS_LOCATION C2D18
J 0
(-1675 3875);
DISPLAY 0.617021 (-1675 3875);
PAINT AQUA (-1675 3875);
DISPLAY INVISIBLE (-1675 3875);
FORCEPROP 2 LAST BOM_COST PROC
J 0
(-1725 3775);
PAINT MONO (-1725 3775);
DISPLAY INVISIBLE (-1725 3775);
FORCEPROP 2 LAST CDS_LIB dev_discrete
J 0
(-1725 3775);
PAINT ORANGE (-1725 3775);
DISPLAY INVISIBLE (-1725 3775);
FORCEPROP 2 LAST CDS_SEC 1
J 0
(-1675 3975);
PAINT MONO (-1675 3975);
DISPLAY INVISIBLE (-1675 3975);
FORCEPROP 2 LAST $SEC 1
J 0
(-1675 3975);
PAINT MONO (-1675 3975);
DISPLAY INVISIBLE (-1675 3975);
FORCEPROP 1 LAST PATH I197
J 0
(-1675 3925);
DISPLAY 0.978723 (-1675 3925);
PAINT WHITE (-1675 3925);
DISPLAY INVISIBLE (-1675 3925);
FORCEPROP 2 LAST ROOM PVCCIN_CPU1_DECAP_VR
J 0
(-1675 3875);
PAINT ORANGE (-1675 3875);
DISPLAY INVISIBLE (-1675 3875);
FORCEPROP 1 LASTPIN (-1725 3875) $PN 1
J 0
(-1715 3855);
DISPLAY 0.787234 (-1715 3855);
PAINT ORANGE (-1715 3855);
DISPLAY INVISIBLE (-1715 3855);
FORCEPROP 1 LASTPIN (-1725 3675) $PN 2
J 0
(-1715 3655);
DISPLAY 0.787234 (-1715 3655);
PAINT ORANGE (-1715 3655);
DISPLAY INVISIBLE (-1715 3655);
FORCEADD CAP_A..1
(-1475 3775);
FORCEPROP 1 LAST VOLTAGE 4V
J 0
(-1425 3775);
DISPLAY 0.617021 (-1425 3775);
PAINT SKYBLUE (-1425 3775);
FORCEPROP 1 LAST VALUE 22.0UF
J 0
(-1425 3825);
DISPLAY 0.617021 (-1425 3825);
PAINT SKYBLUE (-1425 3825);
FORCEPROP 0 LAST GROUP PWR_MCP_CAP
J 0
(-1425 3475);
DISPLAY 0.638298 (-1425 3475);
PAINT BROWN (-1425 3475);
DISPLAY BOTH (-1425 3475);
FORCEPROP 1 LAST PACK_TYPE 0603V
J 0
(-1425 3575);
DISPLAY 0.617021 (-1425 3575);
PAINT SKYBLUE (-1425 3575);
FORCEPROP 1 LAST PART_NUMBER E15431-004
J 0
(-1425 3625);
DISPLAY 0.617021 (-1425 3625);
PAINT BLUE (-1425 3625);
FORCEPROP 1 LAST MATERIAL X6S
J 0
(-1425 3675);
DISPLAY 0.617021 (-1425 3675);
PAINT SKYBLUE (-1425 3675);
FORCEPROP 1 LAST TOLERANCE 20%
J 0
(-1425 3725);
DISPLAY 0.617021 (-1425 3725);
PAINT SKYBLUE (-1425 3725);
FORCEPROP 1 LAST LOCATION C2D28
J 0
(-1425 3875);
DISPLAY 0.617021 (-1425 3875);
PAINT AQUA (-1425 3875);
FORCEPROP 1 LASTPIN (-1475 3675) $PN 2
J 0
(-1465 3655);
DISPLAY 0.787234 (-1465 3655);
PAINT ORANGE (-1465 3655);
DISPLAY INVISIBLE (-1465 3655);
FORCEPROP 1 LASTPIN (-1475 3875) $PN 1
J 0
(-1465 3855);
DISPLAY 0.787234 (-1465 3855);
PAINT ORANGE (-1465 3855);
DISPLAY INVISIBLE (-1465 3855);
FORCEPROP 2 LAST ROOM PVCCIN_CPU1_DECAP_VR
J 0
(-1425 3875);
PAINT ORANGE (-1425 3875);
DISPLAY INVISIBLE (-1425 3875);
FORCEPROP 1 LAST PATH I198
J 0
(-1425 3925);
DISPLAY 0.978723 (-1425 3925);
PAINT WHITE (-1425 3925);
DISPLAY INVISIBLE (-1425 3925);
FORCEPROP 2 LAST $SEC 1
J 0
(-1425 3975);
PAINT MONO (-1425 3975);
DISPLAY INVISIBLE (-1425 3975);
FORCEPROP 2 LAST CDS_SEC 1
J 0
(-1425 3975);
PAINT MONO (-1425 3975);
DISPLAY INVISIBLE (-1425 3975);
FORCEPROP 2 LAST CDS_LIB dev_discrete
J 0
(-1475 3775);
PAINT ORANGE (-1475 3775);
DISPLAY INVISIBLE (-1475 3775);
FORCEPROP 2 LAST BOM_COST PROC
J 0
(-1475 3775);
PAINT MONO (-1475 3775);
DISPLAY INVISIBLE (-1475 3775);
FORCEPROP 2 LAST CDS_LOCATION C2D28
J 0
(-1425 3875);
DISPLAY 0.617021 (-1425 3875);
PAINT AQUA (-1425 3875);
DISPLAY INVISIBLE (-1425 3875);
FORCEADD CAP_A..1
(-1225 3775);
FORCEPROP 0 LAST GROUP PWR_MCP_CAP
J 0
(-1175 3525);
DISPLAY 0.638298 (-1175 3525);
PAINT BROWN (-1175 3525);
DISPLAY BOTH (-1175 3525);
FORCEPROP 1 LAST VALUE 22.0UF
J 0
(-1175 3825);
DISPLAY 0.617021 (-1175 3825);
PAINT SKYBLUE (-1175 3825);
FORCEPROP 1 LAST VOLTAGE 4V
J 0
(-1175 3775);
DISPLAY 0.617021 (-1175 3775);
PAINT SKYBLUE (-1175 3775);
FORCEPROP 1 LAST LOCATION C2D29
J 0
(-1175 3875);
DISPLAY 0.617021 (-1175 3875);
PAINT AQUA (-1175 3875);
FORCEPROP 1 LAST MATERIAL X6S
J 0
(-1175 3675);
DISPLAY 0.617021 (-1175 3675);
PAINT SKYBLUE (-1175 3675);
FORCEPROP 1 LAST TOLERANCE 20%
J 0
(-1175 3725);
DISPLAY 0.617021 (-1175 3725);
PAINT SKYBLUE (-1175 3725);
FORCEPROP 1 LAST PACK_TYPE 0603V
J 0
(-1175 3575);
DISPLAY 0.617021 (-1175 3575);
PAINT SKYBLUE (-1175 3575);
FORCEPROP 1 LAST PART_NUMBER E15431-004
J 0
(-1175 3625);
DISPLAY 0.617021 (-1175 3625);
PAINT BLUE (-1175 3625);
FORCEPROP 1 LASTPIN (-1225 3675) $PN 2
J 0
(-1215 3655);
DISPLAY 0.787234 (-1215 3655);
PAINT ORANGE (-1215 3655);
DISPLAY INVISIBLE (-1215 3655);
FORCEPROP 1 LASTPIN (-1225 3875) $PN 1
J 0
(-1215 3855);
DISPLAY 0.787234 (-1215 3855);
PAINT ORANGE (-1215 3855);
DISPLAY INVISIBLE (-1215 3855);
FORCEPROP 2 LAST ROOM PVCCIN_CPU1_DECAP_VR
J 0
(-1175 3875);
PAINT ORANGE (-1175 3875);
DISPLAY INVISIBLE (-1175 3875);
FORCEPROP 1 LAST PATH I199
J 0
(-1175 3925);
DISPLAY 0.978723 (-1175 3925);
PAINT WHITE (-1175 3925);
DISPLAY INVISIBLE (-1175 3925);
FORCEPROP 2 LAST $SEC 1
J 0
(-1175 3975);
PAINT MONO (-1175 3975);
DISPLAY INVISIBLE (-1175 3975);
FORCEPROP 2 LAST CDS_SEC 1
J 0
(-1175 3975);
PAINT MONO (-1175 3975);
DISPLAY INVISIBLE (-1175 3975);
FORCEPROP 2 LAST CDS_LIB dev_discrete
J 0
(-1225 3775);
PAINT ORANGE (-1225 3775);
DISPLAY INVISIBLE (-1225 3775);
FORCEPROP 2 LAST BOM_COST PROC
J 0
(-1225 3775);
PAINT MONO (-1225 3775);
DISPLAY INVISIBLE (-1225 3775);
FORCEPROP 2 LAST CDS_LOCATION C2D29
J 0
(-1175 3875);
DISPLAY 0.617021 (-1175 3875);
PAINT AQUA (-1175 3875);
DISPLAY INVISIBLE (-1175 3875);
FORCEADD GND..1
(-725 4100);
FORCEPROP 3 LASTPIN (-725 4150) SIG_NAME GND\g
J 0
(-715 4160);
DISPLAY 0.659574 (-715 4160);
PAINT MONO (-715 4160);
DISPLAY INVISIBLE (-715 4160);
FORCEPROP 1 LAST VOLTAGE 0
J 0
(-725 4100);
PAINT SKYBLUE (-725 4100);
DISPLAY INVISIBLE (-725 4100);
FORCEPROP 1 LAST SIZE 1B
J 0
(-650 4050);
DISPLAY 0.893617 (-650 4050);
PAINT GREEN (-650 4050);
DISPLAY INVISIBLE (-650 4050);
FORCEPROP 2 LAST CDS_LIB mstr_symbols
J 0
(-725 4100);
PAINT ORANGE (-725 4100);
DISPLAY INVISIBLE (-725 4100);
FORCEPROP 1 LAST BODY_TYPE PLUMBING
J 0
(-770 4057);
DISPLAY 0.340426 (-770 4057);
PAINT GREEN (-770 4057);
DISPLAY INVISIBLE (-770 4057);
FORCEPROP 1 LAST PATH I2
J 0
(-650 4100);
DISPLAY 0.872340 (-650 4100);
PAINT AQUA (-650 4100);
DISPLAY INVISIBLE (-650 4100);
FORCEPROP 2 LAST ROOM PVCCIN_CPU1_DECAP_VR
J 0
(-1275 4175);
PAINT ORANGE (-1275 4175);
DISPLAY INVISIBLE (-1275 4175);
FORCEPROP 1 LAST HDL_POWER GND
J 0
(-725 4250);
DISPLAY 0.893617 (-725 4250);
PAINT GREEN (-725 4250);
DISPLAY INVISIBLE (-725 4250);
FORCEADD CAP_A..1
(-2100 1150);
FORCEPROP 0 LAST GROUP PWR_MLCC_CAP
J 0
(-2044 937);
DISPLAY 0.638298 (-2044 937);
PAINT BROWN (-2044 937);
DISPLAY BOTH (-2044 937);
FORCEPROP 1 LAST VOLTAGE 4V
J 0
(-2050 1200);
DISPLAY 0.617021 (-2050 1200);
PAINT SKYBLUE (-2050 1200);
FORCEPROP 1 LAST TOLERANCE 20%
J 0
(-2050 1150);
DISPLAY 0.617021 (-2050 1150);
PAINT SKYBLUE (-2050 1150);
FORCEPROP 1 LAST VALUE 22.0UF
J 0
(-2050 1250);
DISPLAY 0.617021 (-2050 1250);
PAINT SKYBLUE (-2050 1250);
FORCEPROP 1 LAST PACK_TYPE 0603V
J 0
(-2050 1000);
DISPLAY 0.617021 (-2050 1000);
PAINT SKYBLUE (-2050 1000);
FORCEPROP 1 LAST MATERIAL X6S
J 0
(-2050 1100);
DISPLAY 0.617021 (-2050 1100);
PAINT SKYBLUE (-2050 1100);
FORCEPROP 1 LAST LOCATION C7P16
J 0
(-2050 1300);
DISPLAY 0.617021 (-2050 1300);
PAINT AQUA (-2050 1300);
FORCEPROP 1 LAST PART_NUMBER E15431-004
J 0
(-2050 1050);
DISPLAY 0.617021 (-2050 1050);
PAINT BLUE (-2050 1050);
FORCEPROP 1 LASTPIN (-2100 1050) $PN 2
J 0
(-2090 1030);
DISPLAY 0.787234 (-2090 1030);
PAINT ORANGE (-2090 1030);
DISPLAY INVISIBLE (-2090 1030);
FORCEPROP 1 LASTPIN (-2100 1250) $PN 1
J 0
(-2090 1230);
DISPLAY 0.787234 (-2090 1230);
PAINT ORANGE (-2090 1230);
DISPLAY INVISIBLE (-2090 1230);
FORCEPROP 2 LAST ROOM PVCCIN_CPU1_DECAP_VR
J 0
(-2050 1250);
PAINT ORANGE (-2050 1250);
DISPLAY INVISIBLE (-2050 1250);
FORCEPROP 1 LAST PATH I206
J 0
(-2050 1300);
DISPLAY 0.978723 (-2050 1300);
PAINT WHITE (-2050 1300);
DISPLAY INVISIBLE (-2050 1300);
FORCEPROP 2 LAST $SEC 1
J 0
(-2050 1350);
PAINT MONO (-2050 1350);
DISPLAY INVISIBLE (-2050 1350);
FORCEPROP 2 LAST CDS_SEC 1
J 0
(-2050 1350);
PAINT MONO (-2050 1350);
DISPLAY INVISIBLE (-2050 1350);
FORCEPROP 2 LAST CDS_LIB dev_discrete
J 0
(-2100 1150);
PAINT ORANGE (-2100 1150);
DISPLAY INVISIBLE (-2100 1150);
FORCEPROP 2 LAST BOM_COST PROC
J 0
(-2100 1150);
PAINT MONO (-2100 1150);
DISPLAY INVISIBLE (-2100 1150);
FORCEPROP 2 LAST CDS_LOCATION C7P16
J 0
(-2050 1250);
DISPLAY 0.617021 (-2050 1250);
PAINT AQUA (-2050 1250);
DISPLAY INVISIBLE (-2050 1250);
FORCEADD CAP_A..1
(-750 3775);
FORCEPROP 0 LAST GROUP PWR_MCP_CAP
J 0
(-675 3525);
DISPLAY 0.638298 (-675 3525);
PAINT BROWN (-675 3525);
DISPLAY BOTH (-675 3525);
FORCEPROP 1 LAST PART_NUMBER E15431-004
J 0
(-700 3625);
DISPLAY 0.617021 (-700 3625);
PAINT BLUE (-700 3625);
FORCEPROP 1 LAST MATERIAL X6S
J 0
(-700 3675);
DISPLAY 0.617021 (-700 3675);
PAINT SKYBLUE (-700 3675);
FORCEPROP 1 LAST TOLERANCE 20%
J 0
(-700 3725);
DISPLAY 0.617021 (-700 3725);
PAINT SKYBLUE (-700 3725);
FORCEPROP 1 LAST LOCATION C3D20
J 0
(-700 3875);
DISPLAY 0.617021 (-700 3875);
PAINT AQUA (-700 3875);
FORCEPROP 1 LAST VALUE 22.0UF
J 0
(-700 3825);
DISPLAY 0.617021 (-700 3825);
PAINT SKYBLUE (-700 3825);
FORCEPROP 1 LAST VOLTAGE 4V
J 0
(-700 3775);
DISPLAY 0.617021 (-700 3775);
PAINT SKYBLUE (-700 3775);
FORCEPROP 1 LAST PACK_TYPE 0603V
J 0
(-700 3575);
DISPLAY 0.617021 (-700 3575);
PAINT SKYBLUE (-700 3575);
FORCEPROP 2 LAST CDS_LOCATION C3D20
J 0
(-700 3875);
DISPLAY 0.617021 (-700 3875);
PAINT AQUA (-700 3875);
DISPLAY INVISIBLE (-700 3875);
FORCEPROP 2 LAST BOM_COST PROC
J 0
(-750 3775);
PAINT MONO (-750 3775);
DISPLAY INVISIBLE (-750 3775);
FORCEPROP 2 LAST CDS_LIB dev_discrete
J 0
(-750 3775);
PAINT ORANGE (-750 3775);
DISPLAY INVISIBLE (-750 3775);
FORCEPROP 2 LAST CDS_SEC 1
J 0
(-700 3975);
PAINT MONO (-700 3975);
DISPLAY INVISIBLE (-700 3975);
FORCEPROP 2 LAST $SEC 1
J 0
(-700 3975);
PAINT MONO (-700 3975);
DISPLAY INVISIBLE (-700 3975);
FORCEPROP 1 LAST PATH I207
J 0
(-700 3925);
DISPLAY 0.978723 (-700 3925);
PAINT WHITE (-700 3925);
DISPLAY INVISIBLE (-700 3925);
FORCEPROP 2 LAST ROOM PVCCIN_CPU1_DECAP_VR
J 0
(-700 3875);
PAINT ORANGE (-700 3875);
DISPLAY INVISIBLE (-700 3875);
FORCEPROP 1 LASTPIN (-750 3875) $PN 1
J 0
(-740 3855);
DISPLAY 0.787234 (-740 3855);
PAINT ORANGE (-740 3855);
DISPLAY INVISIBLE (-740 3855);
FORCEPROP 1 LASTPIN (-750 3675) $PN 2
J 0
(-740 3655);
DISPLAY 0.787234 (-740 3655);
PAINT ORANGE (-740 3655);
DISPLAY INVISIBLE (-740 3655);
FORCEADD CAP_A..1
(-975 3775);
FORCEPROP 0 LAST GROUP PWR_MCP_CAP
J 0
(-925 3475);
DISPLAY 0.638298 (-925 3475);
PAINT BROWN (-925 3475);
DISPLAY BOTH (-925 3475);
FORCEPROP 1 LAST VOLTAGE 4V
J 0
(-925 3775);
DISPLAY 0.617021 (-925 3775);
PAINT SKYBLUE (-925 3775);
FORCEPROP 1 LAST MATERIAL X6S
J 0
(-925 3675);
DISPLAY 0.617021 (-925 3675);
PAINT SKYBLUE (-925 3675);
FORCEPROP 1 LAST PART_NUMBER E15431-004
J 0
(-925 3625);
DISPLAY 0.617021 (-925 3625);
PAINT BLUE (-925 3625);
FORCEPROP 1 LAST LOCATION C3D19
J 0
(-925 3875);
DISPLAY 0.617021 (-925 3875);
PAINT AQUA (-925 3875);
FORCEPROP 1 LAST VALUE 22.0UF
J 0
(-925 3825);
DISPLAY 0.617021 (-925 3825);
PAINT SKYBLUE (-925 3825);
FORCEPROP 1 LAST PACK_TYPE 0603V
J 0
(-925 3575);
DISPLAY 0.617021 (-925 3575);
PAINT SKYBLUE (-925 3575);
FORCEPROP 1 LAST TOLERANCE 20%
J 0
(-925 3725);
DISPLAY 0.617021 (-925 3725);
PAINT SKYBLUE (-925 3725);
FORCEPROP 1 LASTPIN (-975 3675) $PN 2
J 0
(-965 3655);
DISPLAY 0.787234 (-965 3655);
PAINT ORANGE (-965 3655);
DISPLAY INVISIBLE (-965 3655);
FORCEPROP 1 LASTPIN (-975 3875) $PN 1
J 0
(-965 3855);
DISPLAY 0.787234 (-965 3855);
PAINT ORANGE (-965 3855);
DISPLAY INVISIBLE (-965 3855);
FORCEPROP 2 LAST ROOM PVCCIN_CPU1_DECAP_VR
J 0
(-925 3875);
PAINT ORANGE (-925 3875);
DISPLAY INVISIBLE (-925 3875);
FORCEPROP 1 LAST PATH I208
J 0
(-925 3925);
DISPLAY 0.978723 (-925 3925);
PAINT WHITE (-925 3925);
DISPLAY INVISIBLE (-925 3925);
FORCEPROP 2 LAST $SEC 1
J 0
(-925 3975);
PAINT MONO (-925 3975);
DISPLAY INVISIBLE (-925 3975);
FORCEPROP 2 LAST CDS_SEC 1
J 0
(-925 3975);
PAINT MONO (-925 3975);
DISPLAY INVISIBLE (-925 3975);
FORCEPROP 2 LAST CDS_LIB dev_discrete
J 0
(-975 3775);
PAINT ORANGE (-975 3775);
DISPLAY INVISIBLE (-975 3775);
FORCEPROP 2 LAST BOM_COST PROC
J 0
(-975 3775);
PAINT MONO (-975 3775);
DISPLAY INVISIBLE (-975 3775);
FORCEPROP 2 LAST CDS_LOCATION C3D19
J 0
(-925 3875);
DISPLAY 0.617021 (-925 3875);
PAINT AQUA (-925 3875);
DISPLAY INVISIBLE (-925 3875);
FORCEADD VCC_CORE..1
(-1975 4025);
FORCEPROP 3 LASTPIN (-1975 3975) SIG_NAME PVCCMCP_CPU1\g
J 0
(-1965 3985);
DISPLAY 0.659574 (-1965 3985);
PAINT MONO (-1965 3985);
DISPLAY INVISIBLE (-1965 3985);
FORCEPROP 1 LAST HDL_POWER PVCCMCP_CPU1
J 1
(-1975 4075);
DISPLAY 0.617021 (-1975 4075);
PAINT GREEN (-1975 4075);
FORCEPROP 1 LAST PATH I209
J 0
(-1925 4050);
DISPLAY 0.872340 (-1925 4050);
PAINT AQUA (-1925 4050);
DISPLAY INVISIBLE (-1925 4050);
FORCEPROP 2 LAST CDS_LIB mstr_symbols
J 0
(-1975 4025);
PAINT ORANGE (-1975 4025);
DISPLAY INVISIBLE (-1975 4025);
FORCEADD GND..1
(-750 3450);
FORCEPROP 3 LASTPIN (-750 3500) SIG_NAME GND\g
J 0
(-740 3510);
DISPLAY 0.659574 (-740 3510);
PAINT MONO (-740 3510);
DISPLAY INVISIBLE (-740 3510);
FORCEPROP 1 LAST VOLTAGE 0
J 0
(-750 3450);
PAINT SKYBLUE (-750 3450);
DISPLAY INVISIBLE (-750 3450);
FORCEPROP 2 LAST CDS_LIB mstr_symbols
J 0
(-750 3450);
PAINT ORANGE (-750 3450);
DISPLAY INVISIBLE (-750 3450);
FORCEPROP 1 LAST SIZE 1B
J 0
(-675 3400);
DISPLAY 0.893617 (-675 3400);
PAINT GREEN (-675 3400);
DISPLAY INVISIBLE (-675 3400);
FORCEPROP 1 LAST BODY_TYPE PLUMBING
J 0
(-795 3407);
DISPLAY 0.340426 (-795 3407);
PAINT GREEN (-795 3407);
DISPLAY INVISIBLE (-795 3407);
FORCEPROP 1 LAST PATH I210
J 0
(-675 3450);
DISPLAY 0.872340 (-675 3450);
PAINT AQUA (-675 3450);
DISPLAY INVISIBLE (-675 3450);
FORCEPROP 2 LAST ROOM PVCCIN_CPU1_DECAP_VR
J 0
(-1300 3525);
PAINT ORANGE (-1300 3525);
DISPLAY INVISIBLE (-1300 3525);
FORCEPROP 1 LAST HDL_POWER GND
J 0
(-750 3600);
DISPLAY 0.893617 (-750 3600);
PAINT GREEN (-750 3600);
DISPLAY INVISIBLE (-750 3600);
FORCEADD CAP..1
(-6850 2200);
FORCEPROP 1 LASTPIN (-6850 2100) $PN 2
J 0
(-6840 2080);
DISPLAY 0.787234 (-6840 2080);
PAINT ORANGE (-6840 2080);
FORCEPROP 1 LASTPIN (-6850 2300) $PN 1
J 0
(-6840 2280);
DISPLAY 0.787234 (-6840 2280);
PAINT ORANGE (-6840 2280);
FORCEPROP 1 LAST PACK_TYPE 0805
J 0
(-6800 2100);
DISPLAY 0.617021 (-6800 2100);
PAINT SKYBLUE (-6800 2100);
FORCEPROP 1 LAST LOCATION C7P19
J 0
(-6800 2350);
DISPLAY 0.617021 (-6800 2350);
PAINT AQUA (-6800 2350);
FORCEPROP 1 LAST VALUE 47UF
J 0
(-6800 2300);
DISPLAY 0.617021 (-6800 2300);
PAINT SKYBLUE (-6800 2300);
FORCEPROP 1 LAST VOLTAGE 4V
J 0
(-6800 2250);
DISPLAY 0.638298 (-6800 2250);
PAINT SKYBLUE (-6800 2250);
FORCEPROP 1 LAST MATERIAL X6S
J 0
(-6800 2150);
DISPLAY 0.638298 (-6800 2150);
PAINT SKYBLUE (-6800 2150);
FORCEPROP 1 LAST PART_NUMBER C95333-006
R 1
J 0
(-6900 2100);
DISPLAY 0.617021 (-6900 2100);
PAINT BLUE (-6900 2100);
FORCEPROP 1 LAST TOLERANCE 20%
J 0
(-6800 2200);
DISPLAY 0.617021 (-6800 2200);
PAINT SKYBLUE (-6800 2200);
FORCEPROP 0 LAST GROUP PWR_MLCC_CAP
J 0
(-6794 1987);
DISPLAY 0.638298 (-6794 1987);
PAINT BROWN (-6794 1987);
DISPLAY BOTH (-6794 1987);
FORCEPROP 2 LAST SEC_TYPE 0805
J 0
(-6800 2400);
DISPLAY 1.021277 (-6800 2400);
PAINT ORANGE (-6800 2400);
DISPLAY INVISIBLE (-6800 2400);
FORCEPROP 2 LAST SEC 1
J 0
(-6800 2400);
PAINT MONO (-6800 2400);
DISPLAY INVISIBLE (-6800 2400);
FORCEPROP 2 LAST CDS_LIB mstr_discrete
J 0
(-6850 2200);
PAINT ORANGE (-6850 2200);
DISPLAY INVISIBLE (-6850 2200);
FORCEPROP 2 LAST BOM_COST PROC
J 0
(-6850 2200);
PAINT MONO (-6850 2200);
DISPLAY INVISIBLE (-6850 2200);
FORCEPROP 2 LAST CDS_LOCATION C7P19
J 0
(-6800 2300);
DISPLAY 0.617021 (-6800 2300);
PAINT AQUA (-6800 2300);
DISPLAY INVISIBLE (-6800 2300);
FORCEPROP 1 LAST PATH I215
J 0
(-6800 2350);
DISPLAY 0.978723 (-6800 2350);
PAINT WHITE (-6800 2350);
DISPLAY INVISIBLE (-6800 2350);
FORCEPROP 2 LAST ROOM PVCCIN_CPU1_DECAP_VR
J 0
(-6800 2300);
PAINT ORANGE (-6800 2300);
DISPLAY INVISIBLE (-6800 2300);
FORCEADD CAP..1
(-7750 800);
FORCEPROP 1 LASTPIN (-7750 900) $PN 1
J 0
(-7740 880);
DISPLAY 0.787234 (-7740 880);
PAINT ORANGE (-7740 880);
FORCEPROP 1 LAST LOCATION C8P24
J 0
(-7700 950);
DISPLAY 0.617021 (-7700 950);
PAINT AQUA (-7700 950);
FORCEPROP 1 LAST VALUE 47UF
J 0
(-7700 900);
DISPLAY 0.617021 (-7700 900);
PAINT SKYBLUE (-7700 900);
FORCEPROP 1 LAST MATERIAL X6S
J 0
(-7700 750);
DISPLAY 0.638298 (-7700 750);
PAINT SKYBLUE (-7700 750);
FORCEPROP 1 LAST PART_NUMBER C95333-006
R 1
J 0
(-7800 700);
DISPLAY 0.617021 (-7800 700);
PAINT BLUE (-7800 700);
FORCEPROP 1 LASTPIN (-7750 700) $PN 2
J 0
(-7740 680);
DISPLAY 0.787234 (-7740 680);
PAINT ORANGE (-7740 680);
FORCEPROP 1 LAST PACK_TYPE 0805
J 0
(-7700 700);
DISPLAY 0.617021 (-7700 700);
PAINT SKYBLUE (-7700 700);
FORCEPROP 0 LAST GROUP PWR_MLCC_CAP
J 0
(-7694 637);
DISPLAY 0.638298 (-7694 637);
PAINT BROWN (-7694 637);
DISPLAY BOTH (-7694 637);
FORCEPROP 1 LAST VOLTAGE 4V
J 0
(-7700 850);
DISPLAY 0.638298 (-7700 850);
PAINT SKYBLUE (-7700 850);
FORCEPROP 1 LAST TOLERANCE 20%
J 0
(-7700 800);
DISPLAY 0.617021 (-7700 800);
PAINT SKYBLUE (-7700 800);
FORCEPROP 1 LAST PATH I217
J 0
(-7700 950);
DISPLAY 0.978723 (-7700 950);
PAINT WHITE (-7700 950);
DISPLAY INVISIBLE (-7700 950);
FORCEPROP 2 LAST SEC_TYPE 0805
J 0
(-7700 1000);
DISPLAY 1.021277 (-7700 1000);
PAINT ORANGE (-7700 1000);
DISPLAY INVISIBLE (-7700 1000);
FORCEPROP 2 LAST SEC 1
J 0
(-7700 1000);
PAINT MONO (-7700 1000);
DISPLAY INVISIBLE (-7700 1000);
FORCEPROP 2 LAST ROOM PVCCIN_CPU1_DECAP_VR
J 0
(-7700 900);
PAINT ORANGE (-7700 900);
DISPLAY INVISIBLE (-7700 900);
FORCEPROP 2 LAST CDS_LOCATION C8P24
J 0
(-7700 900);
DISPLAY 0.617021 (-7700 900);
PAINT AQUA (-7700 900);
DISPLAY INVISIBLE (-7700 900);
FORCEPROP 2 LAST BOM_COST PROC
J 0
(-7750 800);
PAINT MONO (-7750 800);
DISPLAY INVISIBLE (-7750 800);
FORCEPROP 2 LAST CDS_LIB mstr_discrete
J 0
(-7750 800);
PAINT ORANGE (-7750 800);
DISPLAY INVISIBLE (-7750 800);
FORCEADD GND..1
(-5950 525);
FORCEPROP 3 LASTPIN (-5950 575) SIG_NAME GND\g
J 0
(-5940 585);
DISPLAY 0.659574 (-5940 585);
PAINT MONO (-5940 585);
DISPLAY INVISIBLE (-5940 585);
FORCEPROP 1 LAST PATH I224
J 0
(-5875 525);
DISPLAY 0.872340 (-5875 525);
PAINT AQUA (-5875 525);
DISPLAY INVISIBLE (-5875 525);
FORCEPROP 1 LAST VOLTAGE 0
J 0
(-5950 525);
PAINT SKYBLUE (-5950 525);
DISPLAY INVISIBLE (-5950 525);
FORCEPROP 1 LAST SIZE 1B
J 0
(-5875 475);
DISPLAY 0.893617 (-5875 475);
PAINT GREEN (-5875 475);
DISPLAY INVISIBLE (-5875 475);
FORCEPROP 2 LAST CDS_LIB mstr_symbols
J 0
(-5950 525);
PAINT ORANGE (-5950 525);
DISPLAY INVISIBLE (-5950 525);
FORCEPROP 1 LAST BODY_TYPE PLUMBING
J 0
(-5995 482);
DISPLAY 0.340426 (-5995 482);
PAINT GREEN (-5995 482);
DISPLAY INVISIBLE (-5995 482);
FORCEPROP 2 LAST ROOM PVCCIN_CPU1_DECAP_VR
J 0
(-6500 600);
PAINT ORANGE (-6500 600);
DISPLAY INVISIBLE (-6500 600);
FORCEPROP 1 LAST HDL_POWER GND
J 0
(-5950 675);
DISPLAY 0.893617 (-5950 675);
PAINT GREEN (-5950 675);
DISPLAY INVISIBLE (-5950 675);
FORCEADD GND..1
(-7750 1225);
FORCEPROP 3 LASTPIN (-7750 1275) SIG_NAME GND\g
J 0
(-7740 1285);
DISPLAY 0.659574 (-7740 1285);
PAINT MONO (-7740 1285);
DISPLAY INVISIBLE (-7740 1285);
FORCEPROP 1 LAST PATH I228
J 0
(-7675 1225);
DISPLAY 0.872340 (-7675 1225);
PAINT AQUA (-7675 1225);
DISPLAY INVISIBLE (-7675 1225);
FORCEPROP 1 LAST HDL_POWER GND
J 0
(-7750 1375);
DISPLAY 0.893617 (-7750 1375);
PAINT GREEN (-7750 1375);
DISPLAY INVISIBLE (-7750 1375);
FORCEPROP 2 LAST ROOM PVCCIN_CPU1_DECAP_VR
J 0
(-8300 1300);
PAINT ORANGE (-8300 1300);
DISPLAY INVISIBLE (-8300 1300);
FORCEPROP 1 LAST BODY_TYPE PLUMBING
J 0
(-7795 1182);
DISPLAY 0.340426 (-7795 1182);
PAINT GREEN (-7795 1182);
DISPLAY INVISIBLE (-7795 1182);
FORCEPROP 2 LAST CDS_LIB mstr_symbols
J 0
(-7750 1225);
PAINT ORANGE (-7750 1225);
DISPLAY INVISIBLE (-7750 1225);
FORCEPROP 1 LAST SIZE 1B
J 0
(-7675 1175);
DISPLAY 0.893617 (-7675 1175);
PAINT GREEN (-7675 1175);
DISPLAY INVISIBLE (-7675 1175);
FORCEPROP 1 LAST VOLTAGE 0
J 0
(-7750 1225);
PAINT SKYBLUE (-7750 1225);
DISPLAY INVISIBLE (-7750 1225);
FORCEADD PVCCIN_CPU1..1
(-6550 1800);
FORCEPROP 3 LASTPIN (-6550 1750) SIG_NAME PVCCIN_CPU1\g
J 0
(-6540 1760);
DISPLAY 0.659574 (-6540 1760);
PAINT MONO (-6540 1760);
DISPLAY INVISIBLE (-6540 1760);
FORCEPROP 1 LAST VOLTAGE 2.0V
J 0
(-6595 1757);
DISPLAY 0.340426 (-6595 1757);
PAINT SKYBLUE (-6595 1757);
DISPLAY INVISIBLE (-6595 1757);
FORCEPROP 2 LAST CDS_LIB mstr_symbols
J 0
(-6550 1800);
PAINT ORANGE (-6550 1800);
DISPLAY INVISIBLE (-6550 1800);
FORCEPROP 1 LAST BODY_TYPE PLUMBING
J 0
(-6595 1757);
DISPLAY 0.340426 (-6595 1757);
PAINT GREEN (-6595 1757);
DISPLAY INVISIBLE (-6595 1757);
FORCEPROP 2 LAST ROOM PVCCIN_CPU1_DECAP_VR
J 0
(-6300 1900);
PAINT ORANGE (-6300 1900);
DISPLAY INVISIBLE (-6300 1900);
FORCEPROP 1 LAST HDL_POWER PVCCIN_CPU1
J 1
(-6550 1850);
DISPLAY 0.872340 (-6550 1850);
PAINT GREEN (-6550 1850);
DISPLAY INVISIBLE (-6550 1850);
FORCEPROP 1 LAST PATH I229
J 0
(-6500 1825);
DISPLAY 0.872340 (-6500 1825);
PAINT AQUA (-6500 1825);
DISPLAY INVISIBLE (-6500 1825);
FORCEADD GND..1
(-7750 1925);
FORCEPROP 3 LASTPIN (-7750 1975) SIG_NAME GND\g
J 0
(-7740 1985);
DISPLAY 0.659574 (-7740 1985);
PAINT MONO (-7740 1985);
DISPLAY INVISIBLE (-7740 1985);
FORCEPROP 1 LAST VOLTAGE 0
J 0
(-7750 1925);
PAINT SKYBLUE (-7750 1925);
DISPLAY INVISIBLE (-7750 1925);
FORCEPROP 1 LAST SIZE 1B
J 0
(-7675 1875);
DISPLAY 0.893617 (-7675 1875);
PAINT GREEN (-7675 1875);
DISPLAY INVISIBLE (-7675 1875);
FORCEPROP 2 LAST CDS_LIB mstr_symbols
J 0
(-7750 1925);
PAINT ORANGE (-7750 1925);
DISPLAY INVISIBLE (-7750 1925);
FORCEPROP 1 LAST BODY_TYPE PLUMBING
J 0
(-7795 1882);
DISPLAY 0.340426 (-7795 1882);
PAINT GREEN (-7795 1882);
DISPLAY INVISIBLE (-7795 1882);
FORCEPROP 2 LAST ROOM PVCCIN_CPU1_DECAP_VR
J 0
(-8300 2000);
PAINT ORANGE (-8300 2000);
DISPLAY INVISIBLE (-8300 2000);
FORCEPROP 1 LAST HDL_POWER GND
J 0
(-7750 2075);
DISPLAY 0.893617 (-7750 2075);
PAINT GREEN (-7750 2075);
DISPLAY INVISIBLE (-7750 2075);
FORCEPROP 1 LAST PATH I231
J 0
(-7675 1925);
DISPLAY 0.872340 (-7675 1925);
PAINT AQUA (-7675 1925);
DISPLAY INVISIBLE (-7675 1925);
FORCEADD GND..1
(-5950 1925);
FORCEPROP 3 LASTPIN (-5950 1975) SIG_NAME GND\g
J 0
(-5940 1985);
DISPLAY 0.659574 (-5940 1985);
PAINT MONO (-5940 1985);
DISPLAY INVISIBLE (-5940 1985);
FORCEPROP 1 LAST PATH I233
J 0
(-5875 1925);
DISPLAY 0.872340 (-5875 1925);
PAINT AQUA (-5875 1925);
DISPLAY INVISIBLE (-5875 1925);
FORCEPROP 1 LAST HDL_POWER GND
J 0
(-5950 2075);
DISPLAY 0.893617 (-5950 2075);
PAINT GREEN (-5950 2075);
DISPLAY INVISIBLE (-5950 2075);
FORCEPROP 2 LAST ROOM PVCCIN_CPU1_DECAP_VR
J 0
(-6500 2000);
PAINT ORANGE (-6500 2000);
DISPLAY INVISIBLE (-6500 2000);
FORCEPROP 1 LAST BODY_TYPE PLUMBING
J 0
(-5995 1882);
DISPLAY 0.340426 (-5995 1882);
PAINT GREEN (-5995 1882);
DISPLAY INVISIBLE (-5995 1882);
FORCEPROP 2 LAST CDS_LIB mstr_symbols
J 0
(-5950 1925);
PAINT ORANGE (-5950 1925);
DISPLAY INVISIBLE (-5950 1925);
FORCEPROP 1 LAST SIZE 1B
J 0
(-5875 1875);
DISPLAY 0.893617 (-5875 1875);
PAINT GREEN (-5875 1875);
DISPLAY INVISIBLE (-5875 1875);
FORCEPROP 1 LAST VOLTAGE 0
J 0
(-5950 1925);
PAINT SKYBLUE (-5950 1925);
DISPLAY INVISIBLE (-5950 1925);
FORCEADD GND..1
(-4600 1975);
FORCEPROP 3 LASTPIN (-4600 2025) SIG_NAME GND\g
J 0
(-4590 2035);
DISPLAY 0.659574 (-4590 2035);
PAINT MONO (-4590 2035);
DISPLAY INVISIBLE (-4590 2035);
FORCEPROP 1 LAST VOLTAGE 0
J 0
(-4600 1975);
PAINT SKYBLUE (-4600 1975);
DISPLAY INVISIBLE (-4600 1975);
FORCEPROP 2 LAST CDS_LIB mstr_symbols
J 0
(-4600 1975);
PAINT ORANGE (-4600 1975);
DISPLAY INVISIBLE (-4600 1975);
FORCEPROP 1 LAST SIZE 1B
J 0
(-4525 1925);
DISPLAY 0.893617 (-4525 1925);
PAINT GREEN (-4525 1925);
DISPLAY INVISIBLE (-4525 1925);
FORCEPROP 1 LAST BODY_TYPE PLUMBING
J 0
(-4645 1932);
DISPLAY 0.340426 (-4645 1932);
PAINT GREEN (-4645 1932);
DISPLAY INVISIBLE (-4645 1932);
FORCEPROP 1 LAST PATH I24
J 0
(-4525 1975);
DISPLAY 0.872340 (-4525 1975);
PAINT AQUA (-4525 1975);
DISPLAY INVISIBLE (-4525 1975);
FORCEPROP 2 LAST ROOM PVCCIN_CPU1_DECAP_VR
J 0
(-5150 2050);
PAINT ORANGE (-5150 2050);
DISPLAY INVISIBLE (-5150 2050);
FORCEPROP 1 LAST HDL_POWER GND
J 0
(-4600 2125);
DISPLAY 0.893617 (-4600 2125);
PAINT GREEN (-4600 2125);
DISPLAY INVISIBLE (-4600 2125);
FORCEADD GND..1
(-5950 1225);
FORCEPROP 3 LASTPIN (-5950 1275) SIG_NAME GND\g
J 0
(-5940 1285);
DISPLAY 0.659574 (-5940 1285);
PAINT MONO (-5940 1285);
DISPLAY INVISIBLE (-5940 1285);
FORCEPROP 1 LAST PATH I240
J 0
(-5875 1225);
DISPLAY 0.872340 (-5875 1225);
PAINT AQUA (-5875 1225);
DISPLAY INVISIBLE (-5875 1225);
FORCEPROP 1 LAST HDL_POWER GND
J 0
(-5950 1375);
DISPLAY 0.893617 (-5950 1375);
PAINT GREEN (-5950 1375);
DISPLAY INVISIBLE (-5950 1375);
FORCEPROP 2 LAST ROOM PVCCIN_CPU1_DECAP_VR
J 0
(-6500 1300);
PAINT ORANGE (-6500 1300);
DISPLAY INVISIBLE (-6500 1300);
FORCEPROP 1 LAST BODY_TYPE PLUMBING
J 0
(-5995 1182);
DISPLAY 0.340426 (-5995 1182);
PAINT GREEN (-5995 1182);
DISPLAY INVISIBLE (-5995 1182);
FORCEPROP 1 LAST SIZE 1B
J 0
(-5875 1175);
DISPLAY 0.893617 (-5875 1175);
PAINT GREEN (-5875 1175);
DISPLAY INVISIBLE (-5875 1175);
FORCEPROP 2 LAST CDS_LIB mstr_symbols
J 0
(-5950 1225);
PAINT ORANGE (-5950 1225);
DISPLAY INVISIBLE (-5950 1225);
FORCEPROP 1 LAST VOLTAGE 0
J 0
(-5950 1225);
PAINT SKYBLUE (-5950 1225);
DISPLAY INVISIBLE (-5950 1225);
FORCEADD GND..1
(-1200 1050);
FORCEPROP 3 LASTPIN (-1200 1100) SIG_NAME GND\g
J 0
(-1190 1110);
DISPLAY 0.659574 (-1190 1110);
PAINT MONO (-1190 1110);
DISPLAY INVISIBLE (-1190 1110);
FORCEPROP 1 LAST PATH I241
J 0
(-1125 1050);
DISPLAY 0.872340 (-1125 1050);
PAINT AQUA (-1125 1050);
DISPLAY INVISIBLE (-1125 1050);
FORCEPROP 1 LAST VOLTAGE 0
J 0
(-1200 1050);
PAINT SKYBLUE (-1200 1050);
DISPLAY INVISIBLE (-1200 1050);
FORCEPROP 2 LAST CDS_LIB mstr_symbols
J 0
(-1200 1050);
PAINT ORANGE (-1200 1050);
DISPLAY INVISIBLE (-1200 1050);
FORCEPROP 1 LAST SIZE 1B
J 0
(-1125 1000);
DISPLAY 0.893617 (-1125 1000);
PAINT GREEN (-1125 1000);
DISPLAY INVISIBLE (-1125 1000);
FORCEPROP 1 LAST BODY_TYPE PLUMBING
J 0
(-1245 1007);
DISPLAY 0.340426 (-1245 1007);
PAINT GREEN (-1245 1007);
DISPLAY INVISIBLE (-1245 1007);
FORCEPROP 1 LAST HDL_POWER GND
J 0
(-1200 1200);
DISPLAY 0.893617 (-1200 1200);
PAINT GREEN (-1200 1200);
DISPLAY INVISIBLE (-1200 1200);
FORCEADD PVCCIN_CPU1..1
(-1200 1550);
FORCEPROP 3 LASTPIN (-1200 1500) SIG_NAME PVCCIN_CPU1\g
J 0
(-1190 1510);
DISPLAY 0.659574 (-1190 1510);
PAINT MONO (-1190 1510);
DISPLAY INVISIBLE (-1190 1510);
FORCEPROP 1 LAST VOLTAGE 2.0V
J 0
(-1245 1507);
DISPLAY 0.340426 (-1245 1507);
PAINT SKYBLUE (-1245 1507);
DISPLAY INVISIBLE (-1245 1507);
FORCEPROP 2 LAST CDS_LIB mstr_symbols
J 0
(-1200 1550);
PAINT ORANGE (-1200 1550);
DISPLAY INVISIBLE (-1200 1550);
FORCEPROP 1 LAST BODY_TYPE PLUMBING
J 0
(-1245 1507);
DISPLAY 0.340426 (-1245 1507);
PAINT GREEN (-1245 1507);
DISPLAY INVISIBLE (-1245 1507);
FORCEPROP 2 LAST ROOM PVCCIN_CPU1_DECAP_VR
J 0
(-950 1650);
PAINT ORANGE (-950 1650);
DISPLAY INVISIBLE (-950 1650);
FORCEPROP 1 LAST HDL_POWER PVCCIN_CPU1
J 1
(-1200 1600);
DISPLAY 0.872340 (-1200 1600);
PAINT GREEN (-1200 1600);
DISPLAY INVISIBLE (-1200 1600);
FORCEPROP 1 LAST PATH I244
J 0
(-1150 1575);
DISPLAY 0.872340 (-1150 1575);
PAINT AQUA (-1150 1575);
DISPLAY INVISIBLE (-1150 1575);
FORCEADD CAP..1
(-1200 1300);
FORCEPROP 0 LAST NEW_PN 078.1071T.M002
J 0
(-1153 1099);
DISPLAY 0.638298 (-1153 1099);
PAINT BROWN (-1153 1099);
DISPLAY BOTH (-1153 1099);
FORCEPROP 0 LAST NEW_MATERIAL X6S
J 0
(-1150 1050);
DISPLAY 0.638298 (-1150 1050);
PAINT BROWN (-1150 1050);
DISPLAY BOTH (-1150 1050);
FORCEPROP 0 LAST GROUP PWR_MLCC_CAP
J 0
(-1149 1157);
DISPLAY 0.638298 (-1149 1157);
PAINT BROWN (-1149 1157);
DISPLAY BOTH (-1149 1157);
FORCEPROP 1 LAST PACK_TYPE 0805
J 0
(-1150 1200);
DISPLAY 0.617021 (-1150 1200);
PAINT SKYBLUE (-1150 1200);
FORCEPROP 1 LAST PART_NUMBER 602433-112
J 0
(-1150 1250);
DISPLAY 0.617021 (-1150 1250);
PAINT BLUE (-1150 1250);
FORCEPROP 1 LAST VALUE 100UF
J 0
(-1150 1400);
DISPLAY 0.617021 (-1150 1400);
PAINT SKYBLUE (-1150 1400);
FORCEPROP 1 LAST LOCATION C8W4
J 0
(-1150 1450);
DISPLAY 0.617021 (-1150 1450);
PAINT AQUA (-1150 1450);
FORCEPROP 1 LAST VOLTAGE 4V
J 0
(-1150 1350);
DISPLAY 0.617021 (-1150 1350);
PAINT SKYBLUE (-1150 1350);
FORCEPROP 1 LASTPIN (-1200 1200) $PN 2
J 0
(-1190 1180);
DISPLAY 0.617021 (-1190 1180);
PAINT ORANGE (-1190 1180);
FORCEPROP 1 LAST TOLERANCE 20%
J 0
(-1150 1300);
DISPLAY 0.617021 (-1150 1300);
PAINT SKYBLUE (-1150 1300);
FORCEPROP 1 LASTPIN (-1200 1400) $PN 1
J 0
(-1190 1380);
DISPLAY 0.617021 (-1190 1380);
PAINT ORANGE (-1190 1380);
FORCEPROP 0 LAST CDS_SEC 1
J 0
(-1150 1450);
PAINT MONO (-1150 1450);
DISPLAY INVISIBLE (-1150 1450);
FORCEPROP 2 LAST CDS_LIB mstr_discrete
J 0
(-1200 1300);
PAINT MONO (-1200 1300);
DISPLAY INVISIBLE (-1200 1300);
FORCEPROP 2 LAST BOM_COST MEM_VRD_PVDDQ_CD
J 0
(-1150 1450);
PAINT MONO (-1150 1450);
DISPLAY INVISIBLE (-1150 1450);
FORCEPROP 2 LAST ROOM VDDQ_ABC_PWR_VR
J 0
(-1150 1450);
PAINT MONO (-1150 1450);
DISPLAY INVISIBLE (-1150 1450);
FORCEPROP 2 LAST SEC_TYPE 0805
J 0
(-1150 1500);
DISPLAY 1.021277 (-1150 1500);
PAINT ORANGE (-1150 1500);
DISPLAY INVISIBLE (-1150 1500);
FORCEPROP 2 LAST SEC 1
J 0
(-1150 1500);
DISPLAY 0.680851 (-1150 1500);
PAINT MONO (-1150 1500);
DISPLAY INVISIBLE (-1150 1500);
FORCEPROP 1 LAST MATERIAL X5R
J 0
(-1150 1200);
DISPLAY 0.617021 (-1150 1200);
PAINT SKYBLUE (-1150 1200);
DISPLAY INVISIBLE (-1150 1200);
FORCEPROP 1 LAST PATH I245
J 0
(-1150 1450);
DISPLAY 0.978723 (-1150 1450);
PAINT WHITE (-1150 1450);
DISPLAY INVISIBLE (-1150 1450);
FORCEPROP 2 LAST CDS_LOCATION C8W4
J 0
(-1150 1400);
DISPLAY 0.617021 (-1150 1400);
PAINT AQUA (-1150 1400);
DISPLAY INVISIBLE (-1150 1400);
FORCEADD CAP..1
(-4550 1150);
FORCEPROP 0 LAST GROUP PWR_MLCC_CAP
J 0
(-4494 937);
DISPLAY 0.638298 (-4494 937);
PAINT BROWN (-4494 937);
DISPLAY BOTH (-4494 937);
FORCEPROP 1 LASTPIN (-4550 1050) $PN 2
J 0
(-4540 1030);
DISPLAY 0.617021 (-4540 1030);
PAINT GREEN (-4540 1030);
FORCEPROP 1 LASTPIN (-4550 1250) $PN 1
J 0
(-4540 1230);
DISPLAY 0.617021 (-4540 1230);
PAINT GREEN (-4540 1230);
FORCEPROP 1 LAST VOLTAGE 4V
J 0
(-4500 1200);
DISPLAY 0.638298 (-4500 1200);
PAINT SKYBLUE (-4500 1200);
FORCEPROP 1 LAST VALUE 22UF
J 0
(-4500 1250);
DISPLAY 0.617021 (-4500 1250);
PAINT SKYBLUE (-4500 1250);
FORCEPROP 1 LAST PART_NUMBER C95333-002
J 0
(-4500 1050);
DISPLAY 0.617021 (-4500 1050);
PAINT BLUE (-4500 1050);
FORCEPROP 1 LAST LOCATION C8P5
J 0
(-4500 1300);
DISPLAY 0.617021 (-4500 1300);
PAINT AQUA (-4500 1300);
FORCEPROP 1 LAST TOLERANCE 20%
J 0
(-4500 1150);
DISPLAY 0.617021 (-4500 1150);
PAINT SKYBLUE (-4500 1150);
FORCEPROP 1 LAST PACK_TYPE 0805LF
J 0
(-4500 1000);
DISPLAY 0.617021 (-4500 1000);
PAINT SKYBLUE (-4500 1000);
FORCEPROP 1 LAST MATERIAL X6S
J 0
(-4500 1100);
DISPLAY 0.638298 (-4500 1100);
PAINT SKYBLUE (-4500 1100);
FORCEPROP 2 LAST CDS_LIB mstr_discrete
J 0
(-4550 1150);
PAINT ORANGE (-4550 1150);
DISPLAY INVISIBLE (-4550 1150);
FORCEPROP 2 LAST BOM_COST PROC_SOCKET
J 0
(-4500 1350);
DISPLAY 1.021277 (-4500 1350);
PAINT ORANGE (-4500 1350);
DISPLAY INVISIBLE (-4500 1350);
FORCEPROP 2 LAST CDS_SEC 1
J 0
(-4500 1350);
DISPLAY 1.021277 (-4500 1350);
PAINT ORANGE (-4500 1350);
DISPLAY INVISIBLE (-4500 1350);
FORCEPROP 2 LAST $SEC 1
J 0
(-4500 1350);
DISPLAY 0.680851 (-4500 1350);
PAINT MONO (-4500 1350);
DISPLAY INVISIBLE (-4500 1350);
FORCEPROP 2 LAST ROOM PVCCIN_CPU0_DECAP_VR
J 0
(-4500 1300);
DISPLAY 1.021277 (-4500 1300);
PAINT ORANGE (-4500 1300);
DISPLAY INVISIBLE (-4500 1300);
FORCEPROP 1 LAST PATH I246
J 0
(-4500 1300);
DISPLAY 0.978723 (-4500 1300);
PAINT WHITE (-4500 1300);
DISPLAY INVISIBLE (-4500 1300);
FORCEPROP 2 LAST CDS_LOCATION C8P5
J 0
(-4500 1250);
DISPLAY 0.617021 (-4500 1250);
PAINT AQUA (-4500 1250);
DISPLAY INVISIBLE (-4500 1250);
FORCEADD CAP..1
(-4250 1150);
FORCEPROP 1 LAST PART_NUMBER C95333-002
J 0
(-4200 1050);
DISPLAY 0.617021 (-4200 1050);
PAINT BLUE (-4200 1050);
FORCEPROP 1 LAST TOLERANCE 20%
J 0
(-4200 1150);
DISPLAY 0.617021 (-4200 1150);
PAINT SKYBLUE (-4200 1150);
FORCEPROP 1 LASTPIN (-4250 1050) $PN 2
J 0
(-4240 1030);
DISPLAY 0.617021 (-4240 1030);
PAINT GREEN (-4240 1030);
FORCEPROP 1 LASTPIN (-4250 1250) $PN 1
J 0
(-4240 1230);
DISPLAY 0.617021 (-4240 1230);
PAINT GREEN (-4240 1230);
FORCEPROP 1 LAST MATERIAL X6S
J 0
(-4200 1100);
DISPLAY 0.638298 (-4200 1100);
PAINT SKYBLUE (-4200 1100);
FORCEPROP 1 LAST VOLTAGE 4V
J 0
(-4200 1200);
DISPLAY 0.638298 (-4200 1200);
PAINT SKYBLUE (-4200 1200);
FORCEPROP 1 LAST VALUE 22UF
J 0
(-4200 1250);
DISPLAY 0.617021 (-4200 1250);
PAINT SKYBLUE (-4200 1250);
FORCEPROP 1 LAST LOCATION C8P6
J 0
(-4200 1300);
DISPLAY 0.617021 (-4200 1300);
PAINT AQUA (-4200 1300);
FORCEPROP 1 LAST PACK_TYPE 0805LF
J 0
(-4200 1000);
DISPLAY 0.617021 (-4200 1000);
PAINT SKYBLUE (-4200 1000);
FORCEPROP 0 LAST GROUP PWR_MLCC_CAP
J 0
(-4194 887);
DISPLAY 0.638298 (-4194 887);
PAINT BROWN (-4194 887);
DISPLAY BOTH (-4194 887);
FORCEPROP 2 LAST CDS_LIB mstr_discrete
J 0
(-4250 1150);
PAINT ORANGE (-4250 1150);
DISPLAY INVISIBLE (-4250 1150);
FORCEPROP 2 LAST BOM_COST PROC_SOCKET
J 0
(-4200 1350);
DISPLAY 1.021277 (-4200 1350);
PAINT ORANGE (-4200 1350);
DISPLAY INVISIBLE (-4200 1350);
FORCEPROP 2 LAST CDS_SEC 1
J 0
(-4200 1350);
DISPLAY 1.021277 (-4200 1350);
PAINT ORANGE (-4200 1350);
DISPLAY INVISIBLE (-4200 1350);
FORCEPROP 2 LAST $SEC 1
J 0
(-4200 1350);
DISPLAY 0.680851 (-4200 1350);
PAINT MONO (-4200 1350);
DISPLAY INVISIBLE (-4200 1350);
FORCEPROP 2 LAST ROOM PVCCIN_CPU0_DECAP_VR
J 0
(-4200 1300);
DISPLAY 1.021277 (-4200 1300);
PAINT ORANGE (-4200 1300);
DISPLAY INVISIBLE (-4200 1300);
FORCEPROP 1 LAST PATH I247
J 0
(-4200 1300);
DISPLAY 0.978723 (-4200 1300);
PAINT WHITE (-4200 1300);
DISPLAY INVISIBLE (-4200 1300);
FORCEPROP 2 LAST CDS_LOCATION C8P6
J 0
(-4200 1250);
DISPLAY 0.617021 (-4200 1250);
PAINT AQUA (-4200 1250);
DISPLAY INVISIBLE (-4200 1250);
FORCEADD CAP..1
(-3950 1150);
FORCEPROP 1 LAST LOCATION C8P7
J 0
(-3900 1300);
DISPLAY 0.617021 (-3900 1300);
PAINT AQUA (-3900 1300);
FORCEPROP 1 LAST VALUE 22UF
J 0
(-3900 1250);
DISPLAY 0.617021 (-3900 1250);
PAINT SKYBLUE (-3900 1250);
FORCEPROP 1 LAST TOLERANCE 20%
J 0
(-3900 1150);
DISPLAY 0.617021 (-3900 1150);
PAINT SKYBLUE (-3900 1150);
FORCEPROP 1 LAST PART_NUMBER C95333-002
J 0
(-3900 1050);
DISPLAY 0.617021 (-3900 1050);
PAINT BLUE (-3900 1050);
FORCEPROP 1 LAST PACK_TYPE 0805LF
J 0
(-3900 1000);
DISPLAY 0.617021 (-3900 1000);
PAINT SKYBLUE (-3900 1000);
FORCEPROP 1 LAST VOLTAGE 4V
J 0
(-3900 1200);
DISPLAY 0.638298 (-3900 1200);
PAINT SKYBLUE (-3900 1200);
FORCEPROP 1 LAST MATERIAL X6S
J 0
(-3900 1100);
DISPLAY 0.638298 (-3900 1100);
PAINT SKYBLUE (-3900 1100);
FORCEPROP 1 LASTPIN (-3950 1250) $PN 1
J 0
(-3940 1230);
DISPLAY 0.617021 (-3940 1230);
PAINT GREEN (-3940 1230);
FORCEPROP 1 LASTPIN (-3950 1050) $PN 2
J 0
(-3940 1030);
DISPLAY 0.617021 (-3940 1030);
PAINT GREEN (-3940 1030);
FORCEPROP 0 LAST GROUP PWR_MLCC_CAP
J 0
(-3894 937);
DISPLAY 0.638298 (-3894 937);
PAINT BROWN (-3894 937);
DISPLAY BOTH (-3894 937);
FORCEPROP 1 LAST PATH I248
J 0
(-3900 1300);
DISPLAY 0.978723 (-3900 1300);
PAINT WHITE (-3900 1300);
DISPLAY INVISIBLE (-3900 1300);
FORCEPROP 2 LAST ROOM PVCCIN_CPU0_DECAP_VR
J 0
(-3900 1300);
DISPLAY 1.021277 (-3900 1300);
PAINT ORANGE (-3900 1300);
DISPLAY INVISIBLE (-3900 1300);
FORCEPROP 2 LAST $SEC 1
J 0
(-3900 1350);
DISPLAY 0.680851 (-3900 1350);
PAINT MONO (-3900 1350);
DISPLAY INVISIBLE (-3900 1350);
FORCEPROP 2 LAST CDS_SEC 1
J 0
(-3900 1350);
DISPLAY 1.021277 (-3900 1350);
PAINT ORANGE (-3900 1350);
DISPLAY INVISIBLE (-3900 1350);
FORCEPROP 2 LAST BOM_COST PROC_SOCKET
J 0
(-3900 1350);
DISPLAY 1.021277 (-3900 1350);
PAINT ORANGE (-3900 1350);
DISPLAY INVISIBLE (-3900 1350);
FORCEPROP 2 LAST CDS_LIB mstr_discrete
J 0
(-3950 1150);
PAINT ORANGE (-3950 1150);
DISPLAY INVISIBLE (-3950 1150);
FORCEPROP 2 LAST CDS_LOCATION C8P7
J 0
(-3900 1250);
DISPLAY 0.617021 (-3900 1250);
PAINT AQUA (-3900 1250);
DISPLAY INVISIBLE (-3900 1250);
FORCEADD CAP..1
(-6850 800);
FORCEPROP 1 LAST VOLTAGE 4V
J 0
(-6800 850);
DISPLAY 0.638298 (-6800 850);
PAINT SKYBLUE (-6800 850);
FORCEPROP 1 LASTPIN (-6850 900) $PN 1
J 0
(-6840 880);
DISPLAY 0.787234 (-6840 880);
PAINT ORANGE (-6840 880);
FORCEPROP 1 LASTPIN (-6850 700) $PN 2
J 0
(-6840 680);
DISPLAY 0.787234 (-6840 680);
PAINT ORANGE (-6840 680);
FORCEPROP 1 LAST PACK_TYPE 0805
J 0
(-6800 700);
DISPLAY 0.617021 (-6800 700);
PAINT SKYBLUE (-6800 700);
FORCEPROP 1 LAST VALUE 47UF
J 0
(-6800 900);
DISPLAY 0.617021 (-6800 900);
PAINT SKYBLUE (-6800 900);
FORCEPROP 1 LAST MATERIAL X6S
J 0
(-6800 750);
DISPLAY 0.638298 (-6800 750);
PAINT SKYBLUE (-6800 750);
FORCEPROP 0 LAST GROUP PWR_MLCC_CAP
J 0
(-6794 562);
DISPLAY 0.638298 (-6794 562);
PAINT BROWN (-6794 562);
DISPLAY BOTH (-6794 562);
FORCEPROP 1 LAST LOCATION C8P21
J 0
(-6800 950);
DISPLAY 0.617021 (-6800 950);
PAINT AQUA (-6800 950);
FORCEPROP 1 LAST PART_NUMBER C95333-006
R 1
J 0
(-6900 700);
DISPLAY 0.617021 (-6900 700);
PAINT BLUE (-6900 700);
FORCEPROP 1 LAST TOLERANCE 20%
J 0
(-6800 800);
DISPLAY 0.617021 (-6800 800);
PAINT SKYBLUE (-6800 800);
FORCEPROP 1 LAST PATH I249
J 0
(-6800 950);
DISPLAY 0.978723 (-6800 950);
PAINT WHITE (-6800 950);
DISPLAY INVISIBLE (-6800 950);
FORCEPROP 2 LAST CDS_LIB mstr_discrete
J 0
(-6850 800);
PAINT ORANGE (-6850 800);
DISPLAY INVISIBLE (-6850 800);
FORCEPROP 2 LAST BOM_COST PROC
J 0
(-6850 800);
PAINT MONO (-6850 800);
DISPLAY INVISIBLE (-6850 800);
FORCEPROP 2 LAST ROOM PVCCIN_CPU1_DECAP_VR
J 0
(-6800 900);
PAINT ORANGE (-6800 900);
DISPLAY INVISIBLE (-6800 900);
FORCEPROP 2 LAST SEC 1
J 0
(-6800 1000);
PAINT MONO (-6800 1000);
DISPLAY INVISIBLE (-6800 1000);
FORCEPROP 2 LAST SEC_TYPE 0805
J 0
(-6800 1000);
DISPLAY 1.021277 (-6800 1000);
PAINT ORANGE (-6800 1000);
DISPLAY INVISIBLE (-6800 1000);
FORCEPROP 2 LAST CDS_LOCATION C8P21
J 0
(-6800 900);
DISPLAY 0.617021 (-6800 900);
PAINT AQUA (-6800 900);
DISPLAY INVISIBLE (-6800 900);
FORCEADD CAP..1
(-7450 800);
FORCEPROP 1 LAST VALUE 47UF
J 0
(-7400 900);
DISPLAY 0.617021 (-7400 900);
PAINT SKYBLUE (-7400 900);
FORCEPROP 1 LAST VOLTAGE 4V
J 0
(-7400 850);
DISPLAY 0.638298 (-7400 850);
PAINT SKYBLUE (-7400 850);
FORCEPROP 1 LAST LOCATION C8P27
J 0
(-7400 950);
DISPLAY 0.617021 (-7400 950);
PAINT AQUA (-7400 950);
FORCEPROP 1 LASTPIN (-7450 900) $PN 1
J 0
(-7440 880);
DISPLAY 0.787234 (-7440 880);
PAINT ORANGE (-7440 880);
FORCEPROP 1 LAST MATERIAL X6S
J 0
(-7400 750);
DISPLAY 0.638298 (-7400 750);
PAINT SKYBLUE (-7400 750);
FORCEPROP 0 LAST GROUP PWR_MLCC_CAP
J 0
(-7394 562);
DISPLAY 0.638298 (-7394 562);
PAINT BROWN (-7394 562);
DISPLAY BOTH (-7394 562);
FORCEPROP 1 LASTPIN (-7450 700) $PN 2
J 0
(-7440 680);
DISPLAY 0.787234 (-7440 680);
PAINT ORANGE (-7440 680);
FORCEPROP 1 LAST PACK_TYPE 0805
J 0
(-7400 700);
DISPLAY 0.617021 (-7400 700);
PAINT SKYBLUE (-7400 700);
FORCEPROP 1 LAST PART_NUMBER C95333-006
R 1
J 0
(-7500 700);
DISPLAY 0.617021 (-7500 700);
PAINT BLUE (-7500 700);
FORCEPROP 1 LAST TOLERANCE 20%
J 0
(-7400 800);
DISPLAY 0.617021 (-7400 800);
PAINT SKYBLUE (-7400 800);
FORCEPROP 1 LAST PATH I250
J 0
(-7400 950);
DISPLAY 0.978723 (-7400 950);
PAINT WHITE (-7400 950);
DISPLAY INVISIBLE (-7400 950);
FORCEPROP 2 LAST SEC_TYPE 0805
J 0
(-7400 1000);
DISPLAY 1.021277 (-7400 1000);
PAINT ORANGE (-7400 1000);
DISPLAY INVISIBLE (-7400 1000);
FORCEPROP 2 LAST SEC 1
J 0
(-7400 1000);
PAINT MONO (-7400 1000);
DISPLAY INVISIBLE (-7400 1000);
FORCEPROP 2 LAST ROOM PVCCIN_CPU1_DECAP_VR
J 0
(-7400 900);
PAINT ORANGE (-7400 900);
DISPLAY INVISIBLE (-7400 900);
FORCEPROP 2 LAST BOM_COST PROC
J 0
(-7450 800);
PAINT MONO (-7450 800);
DISPLAY INVISIBLE (-7450 800);
FORCEPROP 2 LAST CDS_LIB mstr_discrete
J 0
(-7450 800);
PAINT ORANGE (-7450 800);
DISPLAY INVISIBLE (-7450 800);
FORCEPROP 2 LAST CDS_LOCATION C8P27
J 0
(-7400 900);
DISPLAY 0.617021 (-7400 900);
PAINT AQUA (-7400 900);
DISPLAY INVISIBLE (-7400 900);
FORCEADD CAP..1
(-7150 800);
FORCEPROP 1 LASTPIN (-7150 900) $PN 1
J 0
(-7140 880);
DISPLAY 0.787234 (-7140 880);
PAINT ORANGE (-7140 880);
FORCEPROP 1 LASTPIN (-7150 700) $PN 2
J 0
(-7140 680);
DISPLAY 0.787234 (-7140 680);
PAINT ORANGE (-7140 680);
FORCEPROP 1 LAST LOCATION C8P25
J 0
(-7100 950);
DISPLAY 0.617021 (-7100 950);
PAINT AQUA (-7100 950);
FORCEPROP 1 LAST PACK_TYPE 0805
J 0
(-7100 700);
DISPLAY 0.617021 (-7100 700);
PAINT SKYBLUE (-7100 700);
FORCEPROP 1 LAST VALUE 47UF
J 0
(-7100 900);
DISPLAY 0.617021 (-7100 900);
PAINT SKYBLUE (-7100 900);
FORCEPROP 1 LAST VOLTAGE 4V
J 0
(-7100 850);
DISPLAY 0.638298 (-7100 850);
PAINT SKYBLUE (-7100 850);
FORCEPROP 1 LAST MATERIAL X6S
J 0
(-7100 750);
DISPLAY 0.638298 (-7100 750);
PAINT SKYBLUE (-7100 750);
FORCEPROP 0 LAST GROUP PWR_MLCC_CAP
J 0
(-7094 637);
DISPLAY 0.638298 (-7094 637);
PAINT BROWN (-7094 637);
DISPLAY BOTH (-7094 637);
FORCEPROP 1 LAST PART_NUMBER C95333-006
R 1
J 0
(-7200 700);
DISPLAY 0.617021 (-7200 700);
PAINT BLUE (-7200 700);
FORCEPROP 1 LAST TOLERANCE 20%
J 0
(-7100 800);
DISPLAY 0.617021 (-7100 800);
PAINT SKYBLUE (-7100 800);
FORCEPROP 1 LAST PATH I251
J 0
(-7100 950);
DISPLAY 0.978723 (-7100 950);
PAINT WHITE (-7100 950);
DISPLAY INVISIBLE (-7100 950);
FORCEPROP 2 LAST SEC_TYPE 0805
J 0
(-7100 1000);
DISPLAY 1.021277 (-7100 1000);
PAINT ORANGE (-7100 1000);
DISPLAY INVISIBLE (-7100 1000);
FORCEPROP 2 LAST SEC 1
J 0
(-7100 1000);
PAINT MONO (-7100 1000);
DISPLAY INVISIBLE (-7100 1000);
FORCEPROP 2 LAST ROOM PVCCIN_CPU1_DECAP_VR
J 0
(-7100 900);
PAINT ORANGE (-7100 900);
DISPLAY INVISIBLE (-7100 900);
FORCEPROP 2 LAST BOM_COST PROC
J 0
(-7150 800);
PAINT MONO (-7150 800);
DISPLAY INVISIBLE (-7150 800);
FORCEPROP 2 LAST CDS_LIB mstr_discrete
J 0
(-7150 800);
PAINT ORANGE (-7150 800);
DISPLAY INVISIBLE (-7150 800);
FORCEPROP 2 LAST CDS_LOCATION C8P25
J 0
(-7100 900);
DISPLAY 0.617021 (-7100 900);
PAINT AQUA (-7100 900);
DISPLAY INVISIBLE (-7100 900);
FORCEADD CAP..1
(-6550 800);
FORCEPROP 1 LAST LOCATION C8P17
J 0
(-6500 950);
DISPLAY 0.617021 (-6500 950);
PAINT AQUA (-6500 950);
FORCEPROP 1 LASTPIN (-6550 700) $PN 2
J 0
(-6540 680);
DISPLAY 0.787234 (-6540 680);
PAINT ORANGE (-6540 680);
FORCEPROP 1 LASTPIN (-6550 900) $PN 1
J 0
(-6540 880);
DISPLAY 0.787234 (-6540 880);
PAINT ORANGE (-6540 880);
FORCEPROP 1 LAST VALUE 47UF
J 0
(-6500 900);
DISPLAY 0.617021 (-6500 900);
PAINT SKYBLUE (-6500 900);
FORCEPROP 1 LAST VOLTAGE 4V
J 0
(-6500 850);
DISPLAY 0.638298 (-6500 850);
PAINT SKYBLUE (-6500 850);
FORCEPROP 1 LAST PACK_TYPE 0805
J 0
(-6500 700);
DISPLAY 0.617021 (-6500 700);
PAINT SKYBLUE (-6500 700);
FORCEPROP 1 LAST MATERIAL X6S
J 0
(-6500 750);
DISPLAY 0.638298 (-6500 750);
PAINT SKYBLUE (-6500 750);
FORCEPROP 0 LAST GROUP PWR_MLCC_CAP
J 0
(-6494 637);
DISPLAY 0.638298 (-6494 637);
PAINT BROWN (-6494 637);
DISPLAY BOTH (-6494 637);
FORCEPROP 1 LAST PART_NUMBER C95333-006
R 1
J 0
(-6600 700);
DISPLAY 0.617021 (-6600 700);
PAINT BLUE (-6600 700);
FORCEPROP 1 LAST TOLERANCE 20%
J 0
(-6500 800);
DISPLAY 0.617021 (-6500 800);
PAINT SKYBLUE (-6500 800);
FORCEPROP 2 LAST CDS_LIB mstr_discrete
J 0
(-6550 800);
PAINT ORANGE (-6550 800);
DISPLAY INVISIBLE (-6550 800);
FORCEPROP 2 LAST BOM_COST PROC
J 0
(-6550 800);
PAINT MONO (-6550 800);
DISPLAY INVISIBLE (-6550 800);
FORCEPROP 2 LAST ROOM PVCCIN_CPU1_DECAP_VR
J 0
(-6500 900);
PAINT ORANGE (-6500 900);
DISPLAY INVISIBLE (-6500 900);
FORCEPROP 2 LAST SEC 1
J 0
(-6500 1000);
PAINT MONO (-6500 1000);
DISPLAY INVISIBLE (-6500 1000);
FORCEPROP 2 LAST SEC_TYPE 0805
J 0
(-6500 1000);
DISPLAY 1.021277 (-6500 1000);
PAINT ORANGE (-6500 1000);
DISPLAY INVISIBLE (-6500 1000);
FORCEPROP 1 LAST PATH I252
J 0
(-6500 950);
DISPLAY 0.978723 (-6500 950);
PAINT WHITE (-6500 950);
DISPLAY INVISIBLE (-6500 950);
FORCEPROP 2 LAST CDS_LOCATION C8P17
J 0
(-6500 900);
DISPLAY 0.617021 (-6500 900);
PAINT AQUA (-6500 900);
DISPLAY INVISIBLE (-6500 900);
FORCEADD GND..1
(-1100 2775);
FORCEPROP 3 LASTPIN (-1100 2825) SIG_NAME GND\g
J 0
(-1090 2835);
DISPLAY 0.659574 (-1090 2835);
PAINT MONO (-1090 2835);
DISPLAY INVISIBLE (-1090 2835);
FORCEPROP 1 LAST PATH I253
J 0
(-1025 2775);
DISPLAY 0.872340 (-1025 2775);
PAINT AQUA (-1025 2775);
DISPLAY INVISIBLE (-1025 2775);
FORCEPROP 1 LAST HDL_POWER GND
J 0
(-1100 2925);
DISPLAY 0.893617 (-1100 2925);
PAINT GREEN (-1100 2925);
DISPLAY INVISIBLE (-1100 2925);
FORCEPROP 1 LAST BODY_TYPE PLUMBING
J 0
(-1145 2732);
DISPLAY 0.340426 (-1145 2732);
PAINT GREEN (-1145 2732);
DISPLAY INVISIBLE (-1145 2732);
FORCEPROP 2 LAST CDS_LIB mstr_symbols
J 0
(-1100 2775);
PAINT ORANGE (-1100 2775);
DISPLAY INVISIBLE (-1100 2775);
FORCEPROP 1 LAST SIZE 1B
J 0
(-1025 2725);
DISPLAY 0.893617 (-1025 2725);
PAINT GREEN (-1025 2725);
DISPLAY INVISIBLE (-1025 2725);
FORCEPROP 1 LAST VOLTAGE 0
J 0
(-1100 2775);
PAINT SKYBLUE (-1100 2775);
DISPLAY INVISIBLE (-1100 2775);
FORCEADD CAP_A..1
(-1100 3050);
FORCEPROP 1 LAST LOCATION C3W4
J 0
(-1050 3200);
DISPLAY 0.617021 (-1050 3200);
PAINT AQUA (-1050 3200);
FORCEPROP 1 LAST MATERIAL X6S
J 0
(-1050 3000);
DISPLAY 0.617021 (-1050 3000);
PAINT SKYBLUE (-1050 3000);
FORCEPROP 1 LAST PART_NUMBER E15431-004
J 0
(-1050 2950);
DISPLAY 0.617021 (-1050 2950);
PAINT BLUE (-1050 2950);
FORCEPROP 1 LAST VOLTAGE 4V
J 0
(-1050 3100);
DISPLAY 0.617021 (-1050 3100);
PAINT SKYBLUE (-1050 3100);
FORCEPROP 1 LAST TOLERANCE 20%
J 0
(-1050 3050);
DISPLAY 0.617021 (-1050 3050);
PAINT SKYBLUE (-1050 3050);
FORCEPROP 1 LAST VALUE 22.0UF
J 0
(-1050 3150);
DISPLAY 0.617021 (-1050 3150);
PAINT SKYBLUE (-1050 3150);
FORCEPROP 1 LAST PACK_TYPE 0603V
J 0
(-1050 2900);
DISPLAY 0.617021 (-1050 2900);
PAINT SKYBLUE (-1050 2900);
FORCEPROP 1 LASTPIN (-1100 3150) $PN 1
J 0
(-1090 3130);
DISPLAY 0.787234 (-1090 3130);
PAINT ORANGE (-1090 3130);
FORCEPROP 1 LASTPIN (-1100 2950) $PN 2
J 0
(-1090 2930);
DISPLAY 0.787234 (-1090 2930);
PAINT ORANGE (-1090 2930);
FORCEPROP 0 LAST GROUP PWR_MCP_CAP
J 0
(-1050 2800);
DISPLAY 0.638298 (-1050 2800);
PAINT BROWN (-1050 2800);
DISPLAY BOTH (-1050 2800);
FORCEPROP 2 LAST CDS_LOCATION C3W4
J 0
(-1050 3150);
DISPLAY 0.617021 (-1050 3150);
PAINT AQUA (-1050 3150);
DISPLAY INVISIBLE (-1050 3150);
FORCEPROP 2 LAST SEC_TYPE 0603V
J 0
(-1050 3250);
DISPLAY 1.021277 (-1050 3250);
PAINT ORANGE (-1050 3250);
DISPLAY INVISIBLE (-1050 3250);
FORCEPROP 2 LAST SEC 1
J 0
(-1050 3250);
PAINT MONO (-1050 3250);
DISPLAY INVISIBLE (-1050 3250);
FORCEPROP 1 LAST PATH I254
J 0
(-1050 3200);
DISPLAY 0.978723 (-1050 3200);
PAINT WHITE (-1050 3200);
DISPLAY INVISIBLE (-1050 3200);
FORCEPROP 2 LAST BOM_COST PROC_SOCKET
J 0
(-1050 3250);
DISPLAY 1.021277 (-1050 3250);
PAINT ORANGE (-1050 3250);
DISPLAY INVISIBLE (-1050 3250);
FORCEPROP 2 LAST CDS_LIB dev_discrete
J 0
(-1100 3050);
PAINT ORANGE (-1100 3050);
DISPLAY INVISIBLE (-1100 3050);
FORCEPROP 2 LAST ROOM PVCCIN_CPU0_DECAP_VR
J 0
(-1050 3200);
DISPLAY 1.021277 (-1050 3200);
PAINT ORANGE (-1050 3200);
DISPLAY INVISIBLE (-1050 3200);
FORCEADD CAP_A..1
(-1400 3050);
FORCEPROP 1 LAST VALUE 22.0UF
J 0
(-1350 3150);
DISPLAY 0.617021 (-1350 3150);
PAINT SKYBLUE (-1350 3150);
FORCEPROP 0 LAST GROUP PWR_MCP_CAP
J 0
(-1350 2850);
DISPLAY 0.638298 (-1350 2850);
PAINT BROWN (-1350 2850);
DISPLAY BOTH (-1350 2850);
FORCEPROP 1 LAST PART_NUMBER E15431-004
J 0
(-1350 2950);
DISPLAY 0.617021 (-1350 2950);
PAINT BLUE (-1350 2950);
FORCEPROP 1 LAST PACK_TYPE 0603V
J 0
(-1350 2900);
DISPLAY 0.617021 (-1350 2900);
PAINT SKYBLUE (-1350 2900);
FORCEPROP 1 LAST MATERIAL X6S
J 0
(-1350 3000);
DISPLAY 0.617021 (-1350 3000);
PAINT SKYBLUE (-1350 3000);
FORCEPROP 1 LAST TOLERANCE 20%
J 0
(-1350 3050);
DISPLAY 0.617021 (-1350 3050);
PAINT SKYBLUE (-1350 3050);
FORCEPROP 1 LAST VOLTAGE 4V
J 0
(-1350 3100);
DISPLAY 0.617021 (-1350 3100);
PAINT SKYBLUE (-1350 3100);
FORCEPROP 1 LASTPIN (-1400 3150) $PN 1
J 0
(-1390 3130);
DISPLAY 0.787234 (-1390 3130);
PAINT ORANGE (-1390 3130);
FORCEPROP 1 LAST LOCATION C3W3
J 0
(-1350 3200);
DISPLAY 0.617021 (-1350 3200);
PAINT AQUA (-1350 3200);
FORCEPROP 1 LASTPIN (-1400 2950) $PN 2
J 0
(-1390 2930);
DISPLAY 0.787234 (-1390 2930);
PAINT ORANGE (-1390 2930);
FORCEPROP 2 LAST CDS_LOCATION C3W3
J 0
(-1350 3150);
DISPLAY 0.617021 (-1350 3150);
PAINT AQUA (-1350 3150);
DISPLAY INVISIBLE (-1350 3150);
FORCEPROP 2 LAST SEC_TYPE 0603V
J 0
(-1350 3250);
DISPLAY 1.021277 (-1350 3250);
PAINT ORANGE (-1350 3250);
DISPLAY INVISIBLE (-1350 3250);
FORCEPROP 2 LAST SEC 1
J 0
(-1350 3250);
PAINT MONO (-1350 3250);
DISPLAY INVISIBLE (-1350 3250);
FORCEPROP 1 LAST PATH I256
J 0
(-1350 3200);
DISPLAY 0.978723 (-1350 3200);
PAINT WHITE (-1350 3200);
DISPLAY INVISIBLE (-1350 3200);
FORCEPROP 2 LAST BOM_COST PROC_SOCKET
J 0
(-1350 3250);
DISPLAY 1.021277 (-1350 3250);
PAINT ORANGE (-1350 3250);
DISPLAY INVISIBLE (-1350 3250);
FORCEPROP 2 LAST CDS_LIB dev_discrete
J 0
(-1400 3050);
PAINT ORANGE (-1400 3050);
DISPLAY INVISIBLE (-1400 3050);
FORCEPROP 2 LAST ROOM PVCCIN_CPU0_DECAP_VR
J 0
(-1350 3200);
DISPLAY 1.021277 (-1350 3200);
PAINT ORANGE (-1350 3200);
DISPLAY INVISIBLE (-1350 3200);
FORCEADD VCC_CORE..1
(-1400 3325);
FORCEPROP 3 LASTPIN (-1400 3275) SIG_NAME PVCCMCP_CPU1\g
J 0
(-1390 3285);
DISPLAY 0.659574 (-1390 3285);
PAINT MONO (-1390 3285);
DISPLAY INVISIBLE (-1390 3285);
FORCEPROP 1 LAST HDL_POWER PVCCMCP_CPU1
J 1
(-1400 3375);
DISPLAY 0.617021 (-1400 3375);
PAINT GREEN (-1400 3375);
FORCEPROP 1 LAST PATH I257
J 0
(-1350 3350);
DISPLAY 0.872340 (-1350 3350);
PAINT AQUA (-1350 3350);
DISPLAY INVISIBLE (-1350 3350);
FORCEPROP 2 LAST CDS_LIB mstr_symbols
J 0
(-1400 3325);
PAINT ORANGE (-1400 3325);
DISPLAY INVISIBLE (-1400 3325);
FORCEADD CAP..1
(-4600 2200);
FORCEPROP 0 LAST NEW_MATERIAL X6S
J 0
(-4550 1950);
DISPLAY 0.638298 (-4550 1950);
PAINT BROWN (-4550 1950);
DISPLAY BOTH (-4550 1950);
FORCEPROP 0 LAST NEW_PN 078.1071T.M002
J 0
(-4553 1999);
DISPLAY 0.638298 (-4553 1999);
PAINT BROWN (-4553 1999);
DISPLAY BOTH (-4553 1999);
FORCEPROP 1 LASTPIN (-4600 2100) $PN 2
J 0
(-4590 2105);
DISPLAY 0.617021 (-4590 2105);
PAINT ORANGE (-4590 2105);
FORCEPROP 1 LAST PACK_TYPE 0805
J 0
(-4500 2125);
DISPLAY 0.617021 (-4500 2125);
PAINT SKYBLUE (-4500 2125);
FORCEPROP 1 LAST LOCATION C7P9
J 0
(-4500 2325);
DISPLAY 0.617021 (-4500 2325);
PAINT AQUA (-4500 2325);
FORCEPROP 1 LASTPIN (-4600 2300) $PN 1
J 0
(-4590 2280);
DISPLAY 0.617021 (-4590 2280);
PAINT ORANGE (-4590 2280);
FORCEPROP 1 LAST VOLTAGE 4V
J 0
(-4500 2225);
DISPLAY 0.617021 (-4500 2225);
PAINT SKYBLUE (-4500 2225);
FORCEPROP 1 LAST TOLERANCE 20%
J 0
(-4500 2175);
DISPLAY 0.617021 (-4500 2175);
PAINT SKYBLUE (-4500 2175);
FORCEPROP 1 LAST VALUE 100UF
J 0
(-4500 2275);
DISPLAY 0.617021 (-4500 2275);
PAINT SKYBLUE (-4500 2275);
FORCEPROP 1 LAST PART_NUMBER 602433-112
R 1
J 0
(-4525 2125);
DISPLAY 0.617021 (-4525 2125);
PAINT BLUE (-4525 2125);
FORCEPROP 0 LAST GROUP PWR_MCP_CAP
J 0
(-4560 1901);
DISPLAY 0.638298 (-4560 1901);
PAINT BROWN (-4560 1901);
DISPLAY BOTH (-4560 1901);
FORCEPROP 2 LAST CDS_LOCATION C7P9
J 0
(-4550 2300);
DISPLAY 0.617021 (-4550 2300);
PAINT AQUA (-4550 2300);
DISPLAY INVISIBLE (-4550 2300);
FORCEPROP 1 LAST PATH I258
J 0
(-4550 2350);
DISPLAY 0.978723 (-4550 2350);
PAINT WHITE (-4550 2350);
DISPLAY INVISIBLE (-4550 2350);
FORCEPROP 1 LAST MATERIAL X5R
J 0
(-4550 2100);
DISPLAY 0.617021 (-4550 2100);
PAINT SKYBLUE (-4550 2100);
DISPLAY INVISIBLE (-4550 2100);
FORCEPROP 2 LAST SEC 1
J 0
(-4550 2400);
DISPLAY 0.680851 (-4550 2400);
PAINT MONO (-4550 2400);
DISPLAY INVISIBLE (-4550 2400);
FORCEPROP 2 LAST SEC_TYPE 0805
J 0
(-4550 2400);
DISPLAY 1.021277 (-4550 2400);
PAINT ORANGE (-4550 2400);
DISPLAY INVISIBLE (-4550 2400);
FORCEPROP 2 LAST ROOM VDDQ_ABC_PWR_VR
J 0
(-4550 2350);
PAINT MONO (-4550 2350);
DISPLAY INVISIBLE (-4550 2350);
FORCEPROP 2 LAST BOM_COST MEM_VRD_PVDDQ_CD
J 0
(-4550 2350);
PAINT MONO (-4550 2350);
DISPLAY INVISIBLE (-4550 2350);
FORCEPROP 2 LAST CDS_LIB mstr_discrete
J 0
(-4600 2200);
PAINT MONO (-4600 2200);
DISPLAY INVISIBLE (-4600 2200);
FORCEPROP 0 LAST CDS_SEC 1
J 0
(-4550 2350);
PAINT MONO (-4550 2350);
DISPLAY INVISIBLE (-4550 2350);
FORCEADD CAP..1
(-4350 2200);
FORCEPROP 1 LAST PART_NUMBER 602433-112
R 1
J 0
(-4275 2125);
DISPLAY 0.617021 (-4275 2125);
PAINT BLUE (-4275 2125);
FORCEPROP 1 LAST TOLERANCE 20%
J 0
(-4250 2175);
DISPLAY 0.617021 (-4250 2175);
PAINT SKYBLUE (-4250 2175);
FORCEPROP 1 LAST VOLTAGE 4V
J 0
(-4250 2225);
DISPLAY 0.617021 (-4250 2225);
PAINT SKYBLUE (-4250 2225);
FORCEPROP 1 LAST VALUE 100UF
J 0
(-4250 2275);
DISPLAY 0.617021 (-4250 2275);
PAINT SKYBLUE (-4250 2275);
FORCEPROP 1 LAST PACK_TYPE 0805
J 0
(-4250 2125);
DISPLAY 0.617021 (-4250 2125);
PAINT SKYBLUE (-4250 2125);
FORCEPROP 1 LASTPIN (-4350 2300) $PN 1
J 0
(-4340 2280);
DISPLAY 0.617021 (-4340 2280);
PAINT ORANGE (-4340 2280);
FORCEPROP 0 LAST NEW_MATERIAL X6S
J 0
(-4300 1800);
DISPLAY 0.638298 (-4300 1800);
PAINT BROWN (-4300 1800);
DISPLAY BOTH (-4300 1800);
FORCEPROP 0 LAST NEW_PN 078.1071T.M002
J 0
(-4303 1849);
DISPLAY 0.638298 (-4303 1849);
PAINT BROWN (-4303 1849);
DISPLAY BOTH (-4303 1849);
FORCEPROP 1 LAST LOCATION C7P5
J 0
(-4250 2325);
DISPLAY 0.617021 (-4250 2325);
PAINT AQUA (-4250 2325);
FORCEPROP 1 LASTPIN (-4350 2100) $PN 2
J 0
(-4340 2105);
DISPLAY 0.617021 (-4340 2105);
PAINT ORANGE (-4340 2105);
FORCEPROP 0 LAST GROUP PWR_MCP_CAP
J 0
(-4310 1751);
DISPLAY 0.638298 (-4310 1751);
PAINT BROWN (-4310 1751);
DISPLAY BOTH (-4310 1751);
FORCEPROP 2 LAST CDS_LOCATION C7P5
J 0
(-4300 2300);
DISPLAY 0.617021 (-4300 2300);
PAINT AQUA (-4300 2300);
DISPLAY INVISIBLE (-4300 2300);
FORCEPROP 1 LAST PATH I259
J 0
(-4300 2350);
DISPLAY 0.978723 (-4300 2350);
PAINT WHITE (-4300 2350);
DISPLAY INVISIBLE (-4300 2350);
FORCEPROP 1 LAST MATERIAL X5R
J 0
(-4300 2100);
DISPLAY 0.617021 (-4300 2100);
PAINT SKYBLUE (-4300 2100);
DISPLAY INVISIBLE (-4300 2100);
FORCEPROP 2 LAST SEC 1
J 0
(-4300 2400);
DISPLAY 0.680851 (-4300 2400);
PAINT MONO (-4300 2400);
DISPLAY INVISIBLE (-4300 2400);
FORCEPROP 2 LAST SEC_TYPE 0805
J 0
(-4300 2400);
DISPLAY 1.021277 (-4300 2400);
PAINT ORANGE (-4300 2400);
DISPLAY INVISIBLE (-4300 2400);
FORCEPROP 2 LAST ROOM VDDQ_ABC_PWR_VR
J 0
(-4300 2350);
PAINT MONO (-4300 2350);
DISPLAY INVISIBLE (-4300 2350);
FORCEPROP 2 LAST BOM_COST MEM_VRD_PVDDQ_CD
J 0
(-4300 2350);
PAINT MONO (-4300 2350);
DISPLAY INVISIBLE (-4300 2350);
FORCEPROP 2 LAST CDS_LIB mstr_discrete
J 0
(-4350 2200);
PAINT MONO (-4350 2200);
DISPLAY INVISIBLE (-4350 2200);
FORCEPROP 0 LAST CDS_SEC 1
J 0
(-4300 2350);
PAINT MONO (-4300 2350);
DISPLAY INVISIBLE (-4300 2350);
FORCEADD CAP..1
(-3850 2200);
FORCEPROP 1 LASTPIN (-3850 2300) $PN 1
J 0
(-3840 2280);
DISPLAY 0.617021 (-3840 2280);
PAINT ORANGE (-3840 2280);
FORCEPROP 1 LAST PART_NUMBER 602433-112
R 1
J 0
(-3775 2125);
DISPLAY 0.617021 (-3775 2125);
PAINT BLUE (-3775 2125);
FORCEPROP 1 LAST LOCATION C8P23
J 0
(-3750 2325);
DISPLAY 0.617021 (-3750 2325);
PAINT AQUA (-3750 2325);
FORCEPROP 1 LAST PACK_TYPE 0805
J 0
(-3750 2125);
DISPLAY 0.617021 (-3750 2125);
PAINT SKYBLUE (-3750 2125);
FORCEPROP 1 LASTPIN (-3850 2100) $PN 2
J 0
(-3840 2105);
DISPLAY 0.617021 (-3840 2105);
PAINT ORANGE (-3840 2105);
FORCEPROP 0 LAST NEW_PN 078.1071T.M002
J 0
(-3803 1849);
DISPLAY 0.638298 (-3803 1849);
PAINT BROWN (-3803 1849);
DISPLAY BOTH (-3803 1849);
FORCEPROP 0 LAST NEW_MATERIAL X6S
J 0
(-3800 1800);
DISPLAY 0.638298 (-3800 1800);
PAINT BROWN (-3800 1800);
DISPLAY BOTH (-3800 1800);
FORCEPROP 1 LAST TOLERANCE 20%
J 0
(-3750 2175);
DISPLAY 0.617021 (-3750 2175);
PAINT SKYBLUE (-3750 2175);
FORCEPROP 1 LAST VOLTAGE 4V
J 0
(-3750 2225);
DISPLAY 0.617021 (-3750 2225);
PAINT SKYBLUE (-3750 2225);
FORCEPROP 1 LAST VALUE 100UF
J 0
(-3750 2275);
DISPLAY 0.617021 (-3750 2275);
PAINT SKYBLUE (-3750 2275);
FORCEPROP 0 LAST GROUP PWR_MCP_CAP
J 0
(-3810 1751);
DISPLAY 0.638298 (-3810 1751);
PAINT BROWN (-3810 1751);
DISPLAY BOTH (-3810 1751);
FORCEPROP 1 LAST PATH I260
J 0
(-3800 2350);
DISPLAY 0.978723 (-3800 2350);
PAINT WHITE (-3800 2350);
DISPLAY INVISIBLE (-3800 2350);
FORCEPROP 1 LAST MATERIAL X5R
J 0
(-3800 2100);
DISPLAY 0.617021 (-3800 2100);
PAINT SKYBLUE (-3800 2100);
DISPLAY INVISIBLE (-3800 2100);
FORCEPROP 2 LAST SEC 1
J 0
(-3800 2400);
DISPLAY 0.680851 (-3800 2400);
PAINT MONO (-3800 2400);
DISPLAY INVISIBLE (-3800 2400);
FORCEPROP 2 LAST SEC_TYPE 0805
J 0
(-3800 2400);
DISPLAY 1.021277 (-3800 2400);
PAINT ORANGE (-3800 2400);
DISPLAY INVISIBLE (-3800 2400);
FORCEPROP 2 LAST ROOM VDDQ_ABC_PWR_VR
J 0
(-3800 2350);
PAINT MONO (-3800 2350);
DISPLAY INVISIBLE (-3800 2350);
FORCEPROP 2 LAST BOM_COST MEM_VRD_PVDDQ_CD
J 0
(-3800 2350);
PAINT MONO (-3800 2350);
DISPLAY INVISIBLE (-3800 2350);
FORCEPROP 2 LAST CDS_LIB mstr_discrete
J 0
(-3850 2200);
PAINT MONO (-3850 2200);
DISPLAY INVISIBLE (-3850 2200);
FORCEPROP 0 LAST CDS_SEC 1
J 0
(-3800 2350);
PAINT MONO (-3800 2350);
DISPLAY INVISIBLE (-3800 2350);
FORCEPROP 2 LAST CDS_LOCATION C8P23
J 0
(-3800 2300);
DISPLAY 0.617021 (-3800 2300);
PAINT AQUA (-3800 2300);
DISPLAY INVISIBLE (-3800 2300);
FORCEADD CAP..1
(-4100 2200);
FORCEPROP 1 LAST PART_NUMBER 602433-112
R 1
J 0
(-4025 2125);
DISPLAY 0.617021 (-4025 2125);
PAINT BLUE (-4025 2125);
FORCEPROP 1 LAST LOCATION C7P14
J 0
(-4000 2325);
DISPLAY 0.617021 (-4000 2325);
PAINT AQUA (-4000 2325);
FORCEPROP 1 LAST VOLTAGE 4V
J 0
(-4000 2225);
DISPLAY 0.617021 (-4000 2225);
PAINT SKYBLUE (-4000 2225);
FORCEPROP 1 LAST VALUE 100UF
J 0
(-4000 2275);
DISPLAY 0.617021 (-4000 2275);
PAINT SKYBLUE (-4000 2275);
FORCEPROP 1 LAST PACK_TYPE 0805
J 0
(-4000 2125);
DISPLAY 0.617021 (-4000 2125);
PAINT SKYBLUE (-4000 2125);
FORCEPROP 1 LASTPIN (-4100 2100) $PN 2
J 0
(-4090 2105);
DISPLAY 0.617021 (-4090 2105);
PAINT ORANGE (-4090 2105);
FORCEPROP 0 LAST NEW_PN 078.1071T.M002
J 0
(-4053 1999);
DISPLAY 0.638298 (-4053 1999);
PAINT BROWN (-4053 1999);
DISPLAY BOTH (-4053 1999);
FORCEPROP 1 LASTPIN (-4100 2300) $PN 1
J 0
(-4090 2280);
DISPLAY 0.617021 (-4090 2280);
PAINT ORANGE (-4090 2280);
FORCEPROP 0 LAST NEW_MATERIAL X6S
J 0
(-4050 1950);
DISPLAY 0.638298 (-4050 1950);
PAINT BROWN (-4050 1950);
DISPLAY BOTH (-4050 1950);
FORCEPROP 1 LAST TOLERANCE 20%
J 0
(-4000 2175);
DISPLAY 0.617021 (-4000 2175);
PAINT SKYBLUE (-4000 2175);
FORCEPROP 0 LAST GROUP PWR_MCP_CAP
J 0
(-4060 1901);
DISPLAY 0.638298 (-4060 1901);
PAINT BROWN (-4060 1901);
DISPLAY BOTH (-4060 1901);
FORCEPROP 1 LAST PATH I261
J 0
(-4050 2350);
DISPLAY 0.978723 (-4050 2350);
PAINT WHITE (-4050 2350);
DISPLAY INVISIBLE (-4050 2350);
FORCEPROP 1 LAST MATERIAL X5R
J 0
(-4050 2100);
DISPLAY 0.617021 (-4050 2100);
PAINT SKYBLUE (-4050 2100);
DISPLAY INVISIBLE (-4050 2100);
FORCEPROP 2 LAST SEC 1
J 0
(-4050 2400);
DISPLAY 0.680851 (-4050 2400);
PAINT MONO (-4050 2400);
DISPLAY INVISIBLE (-4050 2400);
FORCEPROP 2 LAST SEC_TYPE 0805
J 0
(-4050 2400);
DISPLAY 1.021277 (-4050 2400);
PAINT ORANGE (-4050 2400);
DISPLAY INVISIBLE (-4050 2400);
FORCEPROP 2 LAST ROOM VDDQ_ABC_PWR_VR
J 0
(-4050 2350);
PAINT MONO (-4050 2350);
DISPLAY INVISIBLE (-4050 2350);
FORCEPROP 2 LAST BOM_COST MEM_VRD_PVDDQ_CD
J 0
(-4050 2350);
PAINT MONO (-4050 2350);
DISPLAY INVISIBLE (-4050 2350);
FORCEPROP 2 LAST CDS_LIB mstr_discrete
J 0
(-4100 2200);
PAINT MONO (-4100 2200);
DISPLAY INVISIBLE (-4100 2200);
FORCEPROP 0 LAST CDS_SEC 1
J 0
(-4050 2350);
PAINT MONO (-4050 2350);
DISPLAY INVISIBLE (-4050 2350);
FORCEPROP 2 LAST CDS_LOCATION C7P14
J 0
(-4050 2300);
DISPLAY 0.617021 (-4050 2300);
PAINT AQUA (-4050 2300);
DISPLAY INVISIBLE (-4050 2300);
FORCEADD CAP..1
(-3350 2200);
FORCEPROP 1 LAST PART_NUMBER 602433-112
R 1
J 0
(-3275 2125);
DISPLAY 0.617021 (-3275 2125);
PAINT BLUE (-3275 2125);
FORCEPROP 1 LAST TOLERANCE 20%
J 0
(-3250 2175);
DISPLAY 0.617021 (-3250 2175);
PAINT SKYBLUE (-3250 2175);
FORCEPROP 1 LAST PACK_TYPE 0805
J 0
(-3250 2125);
DISPLAY 0.617021 (-3250 2125);
PAINT SKYBLUE (-3250 2125);
FORCEPROP 0 LAST NEW_PN 078.1071T.M002
J 0
(-3303 1849);
DISPLAY 0.638298 (-3303 1849);
PAINT BROWN (-3303 1849);
DISPLAY BOTH (-3303 1849);
FORCEPROP 0 LAST NEW_MATERIAL X6S
J 0
(-3300 1800);
DISPLAY 0.638298 (-3300 1800);
PAINT BROWN (-3300 1800);
DISPLAY BOTH (-3300 1800);
FORCEPROP 1 LAST VALUE 100UF
J 0
(-3250 2275);
DISPLAY 0.617021 (-3250 2275);
PAINT SKYBLUE (-3250 2275);
FORCEPROP 1 LAST LOCATION C7P11
J 0
(-3250 2325);
DISPLAY 0.617021 (-3250 2325);
PAINT AQUA (-3250 2325);
FORCEPROP 1 LAST VOLTAGE 4V
J 0
(-3250 2225);
DISPLAY 0.617021 (-3250 2225);
PAINT SKYBLUE (-3250 2225);
FORCEPROP 1 LASTPIN (-3350 2100) $PN 2
J 0
(-3340 2105);
DISPLAY 0.617021 (-3340 2105);
PAINT ORANGE (-3340 2105);
FORCEPROP 1 LASTPIN (-3350 2300) $PN 1
J 0
(-3340 2280);
DISPLAY 0.617021 (-3340 2280);
PAINT ORANGE (-3340 2280);
FORCEPROP 0 LAST GROUP PWR_MCP_CAP
J 0
(-3310 1751);
DISPLAY 0.638298 (-3310 1751);
PAINT BROWN (-3310 1751);
DISPLAY BOTH (-3310 1751);
FORCEPROP 1 LAST PATH I262
J 0
(-3300 2350);
DISPLAY 0.978723 (-3300 2350);
PAINT WHITE (-3300 2350);
DISPLAY INVISIBLE (-3300 2350);
FORCEPROP 0 LAST CDS_SEC 1
J 0
(-3300 2350);
PAINT MONO (-3300 2350);
DISPLAY INVISIBLE (-3300 2350);
FORCEPROP 2 LAST CDS_LIB mstr_discrete
J 0
(-3350 2200);
PAINT MONO (-3350 2200);
DISPLAY INVISIBLE (-3350 2200);
FORCEPROP 2 LAST BOM_COST MEM_VRD_PVDDQ_CD
J 0
(-3300 2350);
PAINT MONO (-3300 2350);
DISPLAY INVISIBLE (-3300 2350);
FORCEPROP 2 LAST ROOM VDDQ_ABC_PWR_VR
J 0
(-3300 2350);
PAINT MONO (-3300 2350);
DISPLAY INVISIBLE (-3300 2350);
FORCEPROP 2 LAST SEC_TYPE 0805
J 0
(-3300 2400);
DISPLAY 1.021277 (-3300 2400);
PAINT ORANGE (-3300 2400);
DISPLAY INVISIBLE (-3300 2400);
FORCEPROP 2 LAST SEC 1
J 0
(-3300 2400);
DISPLAY 0.680851 (-3300 2400);
PAINT MONO (-3300 2400);
DISPLAY INVISIBLE (-3300 2400);
FORCEPROP 1 LAST MATERIAL X5R
J 0
(-3300 2100);
DISPLAY 0.617021 (-3300 2100);
PAINT SKYBLUE (-3300 2100);
DISPLAY INVISIBLE (-3300 2100);
FORCEPROP 2 LAST CDS_LOCATION C7P11
J 0
(-3300 2300);
DISPLAY 0.617021 (-3300 2300);
PAINT AQUA (-3300 2300);
DISPLAY INVISIBLE (-3300 2300);
FORCEADD CAP..1
(-3600 2200);
FORCEPROP 1 LAST PART_NUMBER 602433-112
R 1
J 0
(-3525 2125);
DISPLAY 0.617021 (-3525 2125);
PAINT BLUE (-3525 2125);
FORCEPROP 1 LAST LOCATION C7P15
J 0
(-3500 2325);
DISPLAY 0.617021 (-3500 2325);
PAINT AQUA (-3500 2325);
FORCEPROP 1 LAST VALUE 100UF
J 0
(-3500 2275);
DISPLAY 0.617021 (-3500 2275);
PAINT SKYBLUE (-3500 2275);
FORCEPROP 1 LAST PACK_TYPE 0805
J 0
(-3500 2125);
DISPLAY 0.617021 (-3500 2125);
PAINT SKYBLUE (-3500 2125);
FORCEPROP 0 LAST NEW_PN 078.1071T.M002
J 0
(-3553 1999);
DISPLAY 0.638298 (-3553 1999);
PAINT BROWN (-3553 1999);
DISPLAY BOTH (-3553 1999);
FORCEPROP 0 LAST NEW_MATERIAL X6S
J 0
(-3550 1950);
DISPLAY 0.638298 (-3550 1950);
PAINT BROWN (-3550 1950);
DISPLAY BOTH (-3550 1950);
FORCEPROP 1 LASTPIN (-3600 2100) $PN 2
J 0
(-3590 2105);
DISPLAY 0.617021 (-3590 2105);
PAINT ORANGE (-3590 2105);
FORCEPROP 1 LAST TOLERANCE 20%
J 0
(-3500 2175);
DISPLAY 0.617021 (-3500 2175);
PAINT SKYBLUE (-3500 2175);
FORCEPROP 1 LAST VOLTAGE 4V
J 0
(-3500 2225);
DISPLAY 0.617021 (-3500 2225);
PAINT SKYBLUE (-3500 2225);
FORCEPROP 1 LASTPIN (-3600 2300) $PN 1
J 0
(-3590 2280);
DISPLAY 0.617021 (-3590 2280);
PAINT ORANGE (-3590 2280);
FORCEPROP 0 LAST GROUP PWR_MCP_CAP
J 0
(-3560 1901);
DISPLAY 0.638298 (-3560 1901);
PAINT BROWN (-3560 1901);
DISPLAY BOTH (-3560 1901);
FORCEPROP 1 LAST PATH I263
J 0
(-3550 2350);
DISPLAY 0.978723 (-3550 2350);
PAINT WHITE (-3550 2350);
DISPLAY INVISIBLE (-3550 2350);
FORCEPROP 0 LAST CDS_SEC 1
J 0
(-3550 2350);
PAINT MONO (-3550 2350);
DISPLAY INVISIBLE (-3550 2350);
FORCEPROP 2 LAST CDS_LIB mstr_discrete
J 0
(-3600 2200);
PAINT MONO (-3600 2200);
DISPLAY INVISIBLE (-3600 2200);
FORCEPROP 2 LAST BOM_COST MEM_VRD_PVDDQ_CD
J 0
(-3550 2350);
PAINT MONO (-3550 2350);
DISPLAY INVISIBLE (-3550 2350);
FORCEPROP 2 LAST ROOM VDDQ_ABC_PWR_VR
J 0
(-3550 2350);
PAINT MONO (-3550 2350);
DISPLAY INVISIBLE (-3550 2350);
FORCEPROP 2 LAST SEC_TYPE 0805
J 0
(-3550 2400);
DISPLAY 1.021277 (-3550 2400);
PAINT ORANGE (-3550 2400);
DISPLAY INVISIBLE (-3550 2400);
FORCEPROP 2 LAST SEC 1
J 0
(-3550 2400);
DISPLAY 0.680851 (-3550 2400);
PAINT MONO (-3550 2400);
DISPLAY INVISIBLE (-3550 2400);
FORCEPROP 1 LAST MATERIAL X5R
J 0
(-3550 2100);
DISPLAY 0.617021 (-3550 2100);
PAINT SKYBLUE (-3550 2100);
DISPLAY INVISIBLE (-3550 2100);
FORCEPROP 2 LAST CDS_LOCATION C7P15
J 0
(-3550 2300);
DISPLAY 0.617021 (-3550 2300);
PAINT AQUA (-3550 2300);
DISPLAY INVISIBLE (-3550 2300);
FORCEADD CAP..1
(-2850 2200);
FORCEPROP 0 LAST NEW_PN 078.1071T.M002
J 0
(-2803 1849);
DISPLAY 0.638298 (-2803 1849);
PAINT BROWN (-2803 1849);
DISPLAY BOTH (-2803 1849);
FORCEPROP 1 LAST PART_NUMBER 602433-112
R 1
J 0
(-2775 2125);
DISPLAY 0.617021 (-2775 2125);
PAINT BLUE (-2775 2125);
FORCEPROP 1 LAST LOCATION C8P22
J 0
(-2750 2325);
DISPLAY 0.617021 (-2750 2325);
PAINT AQUA (-2750 2325);
FORCEPROP 1 LASTPIN (-2850 2300) $PN 1
J 0
(-2840 2280);
DISPLAY 0.617021 (-2840 2280);
PAINT ORANGE (-2840 2280);
FORCEPROP 1 LAST VOLTAGE 4V
J 0
(-2750 2225);
DISPLAY 0.617021 (-2750 2225);
PAINT SKYBLUE (-2750 2225);
FORCEPROP 1 LAST VALUE 100UF
J 0
(-2750 2275);
DISPLAY 0.617021 (-2750 2275);
PAINT SKYBLUE (-2750 2275);
FORCEPROP 0 LAST NEW_MATERIAL X6S
J 0
(-2800 1800);
DISPLAY 0.638298 (-2800 1800);
PAINT BROWN (-2800 1800);
DISPLAY BOTH (-2800 1800);
FORCEPROP 1 LASTPIN (-2850 2100) $PN 2
J 0
(-2840 2105);
DISPLAY 0.617021 (-2840 2105);
PAINT ORANGE (-2840 2105);
FORCEPROP 1 LAST PACK_TYPE 0805
J 0
(-2750 2125);
DISPLAY 0.617021 (-2750 2125);
PAINT SKYBLUE (-2750 2125);
FORCEPROP 1 LAST TOLERANCE 20%
J 0
(-2750 2175);
DISPLAY 0.617021 (-2750 2175);
PAINT SKYBLUE (-2750 2175);
FORCEPROP 0 LAST GROUP PWR_MCP_CAP
J 0
(-2810 1751);
DISPLAY 0.638298 (-2810 1751);
PAINT BROWN (-2810 1751);
DISPLAY BOTH (-2810 1751);
FORCEPROP 1 LAST PATH I264
J 0
(-2800 2350);
DISPLAY 0.978723 (-2800 2350);
PAINT WHITE (-2800 2350);
DISPLAY INVISIBLE (-2800 2350);
FORCEPROP 1 LAST MATERIAL X5R
J 0
(-2800 2100);
DISPLAY 0.617021 (-2800 2100);
PAINT SKYBLUE (-2800 2100);
DISPLAY INVISIBLE (-2800 2100);
FORCEPROP 2 LAST SEC 1
J 0
(-2800 2400);
DISPLAY 0.680851 (-2800 2400);
PAINT MONO (-2800 2400);
DISPLAY INVISIBLE (-2800 2400);
FORCEPROP 2 LAST SEC_TYPE 0805
J 0
(-2800 2400);
DISPLAY 1.021277 (-2800 2400);
PAINT ORANGE (-2800 2400);
DISPLAY INVISIBLE (-2800 2400);
FORCEPROP 2 LAST ROOM VDDQ_ABC_PWR_VR
J 0
(-2800 2350);
PAINT MONO (-2800 2350);
DISPLAY INVISIBLE (-2800 2350);
FORCEPROP 2 LAST BOM_COST MEM_VRD_PVDDQ_CD
J 0
(-2800 2350);
PAINT MONO (-2800 2350);
DISPLAY INVISIBLE (-2800 2350);
FORCEPROP 2 LAST CDS_LIB mstr_discrete
J 0
(-2850 2200);
PAINT MONO (-2850 2200);
DISPLAY INVISIBLE (-2850 2200);
FORCEPROP 0 LAST CDS_SEC 1
J 0
(-2800 2350);
PAINT MONO (-2800 2350);
DISPLAY INVISIBLE (-2800 2350);
FORCEPROP 2 LAST CDS_LOCATION C8P22
J 0
(-2800 2300);
DISPLAY 0.617021 (-2800 2300);
PAINT AQUA (-2800 2300);
DISPLAY INVISIBLE (-2800 2300);
FORCEADD CAP..1
(-3100 2200);
FORCEPROP 0 LAST NEW_PN 078.1071T.M002
J 0
(-3053 1999);
DISPLAY 0.638298 (-3053 1999);
PAINT BROWN (-3053 1999);
DISPLAY BOTH (-3053 1999);
FORCEPROP 0 LAST NEW_MATERIAL X6S
J 0
(-3050 1950);
DISPLAY 0.638298 (-3050 1950);
PAINT BROWN (-3050 1950);
DISPLAY BOTH (-3050 1950);
FORCEPROP 1 LAST PART_NUMBER 602433-112
R 1
J 0
(-3025 2125);
DISPLAY 0.617021 (-3025 2125);
PAINT BLUE (-3025 2125);
FORCEPROP 1 LAST VALUE 100UF
J 0
(-3000 2275);
DISPLAY 0.617021 (-3000 2275);
PAINT SKYBLUE (-3000 2275);
FORCEPROP 1 LAST LOCATION C7P8
J 0
(-3000 2325);
DISPLAY 0.617021 (-3000 2325);
PAINT AQUA (-3000 2325);
FORCEPROP 1 LAST TOLERANCE 20%
J 0
(-3000 2175);
DISPLAY 0.617021 (-3000 2175);
PAINT SKYBLUE (-3000 2175);
FORCEPROP 1 LASTPIN (-3100 2100) $PN 2
J 0
(-3090 2105);
DISPLAY 0.617021 (-3090 2105);
PAINT ORANGE (-3090 2105);
FORCEPROP 1 LASTPIN (-3100 2300) $PN 1
J 0
(-3090 2280);
DISPLAY 0.617021 (-3090 2280);
PAINT ORANGE (-3090 2280);
FORCEPROP 1 LAST VOLTAGE 4V
J 0
(-3000 2225);
DISPLAY 0.617021 (-3000 2225);
PAINT SKYBLUE (-3000 2225);
FORCEPROP 1 LAST PACK_TYPE 0805
J 0
(-3000 2125);
DISPLAY 0.617021 (-3000 2125);
PAINT SKYBLUE (-3000 2125);
FORCEPROP 0 LAST GROUP PWR_MCP_CAP
J 0
(-3060 1901);
DISPLAY 0.638298 (-3060 1901);
PAINT BROWN (-3060 1901);
DISPLAY BOTH (-3060 1901);
FORCEPROP 1 LAST PATH I265
J 0
(-3050 2350);
DISPLAY 0.978723 (-3050 2350);
PAINT WHITE (-3050 2350);
DISPLAY INVISIBLE (-3050 2350);
FORCEPROP 1 LAST MATERIAL X5R
J 0
(-3050 2100);
DISPLAY 0.617021 (-3050 2100);
PAINT SKYBLUE (-3050 2100);
DISPLAY INVISIBLE (-3050 2100);
FORCEPROP 2 LAST SEC 1
J 0
(-3050 2400);
DISPLAY 0.680851 (-3050 2400);
PAINT MONO (-3050 2400);
DISPLAY INVISIBLE (-3050 2400);
FORCEPROP 2 LAST SEC_TYPE 0805
J 0
(-3050 2400);
DISPLAY 1.021277 (-3050 2400);
PAINT ORANGE (-3050 2400);
DISPLAY INVISIBLE (-3050 2400);
FORCEPROP 2 LAST ROOM VDDQ_ABC_PWR_VR
J 0
(-3050 2350);
PAINT MONO (-3050 2350);
DISPLAY INVISIBLE (-3050 2350);
FORCEPROP 2 LAST BOM_COST MEM_VRD_PVDDQ_CD
J 0
(-3050 2350);
PAINT MONO (-3050 2350);
DISPLAY INVISIBLE (-3050 2350);
FORCEPROP 2 LAST CDS_LIB mstr_discrete
J 0
(-3100 2200);
PAINT MONO (-3100 2200);
DISPLAY INVISIBLE (-3100 2200);
FORCEPROP 0 LAST CDS_SEC 1
J 0
(-3050 2350);
PAINT MONO (-3050 2350);
DISPLAY INVISIBLE (-3050 2350);
FORCEPROP 2 LAST CDS_LOCATION C7P8
J 0
(-3050 2300);
DISPLAY 0.617021 (-3050 2300);
PAINT AQUA (-3050 2300);
DISPLAY INVISIBLE (-3050 2300);
FORCEADD CAP..1
(-2350 2200);
FORCEPROP 0 LAST NEW_MATERIAL X6S
J 0
(-2300 1800);
DISPLAY 0.638298 (-2300 1800);
PAINT BROWN (-2300 1800);
DISPLAY BOTH (-2300 1800);
FORCEPROP 0 LAST NEW_PN 078.1071T.M002
J 0
(-2303 1849);
DISPLAY 0.638298 (-2303 1849);
PAINT BROWN (-2303 1849);
DISPLAY BOTH (-2303 1849);
FORCEPROP 1 LAST PART_NUMBER 602433-112
R 1
J 0
(-2275 2125);
DISPLAY 0.617021 (-2275 2125);
PAINT BLUE (-2275 2125);
FORCEPROP 1 LAST LOCATION C7P10
J 0
(-2250 2325);
DISPLAY 0.617021 (-2250 2325);
PAINT AQUA (-2250 2325);
FORCEPROP 1 LAST VALUE 100UF
J 0
(-2250 2275);
DISPLAY 0.617021 (-2250 2275);
PAINT SKYBLUE (-2250 2275);
FORCEPROP 1 LAST VOLTAGE 4V
J 0
(-2250 2225);
DISPLAY 0.617021 (-2250 2225);
PAINT SKYBLUE (-2250 2225);
FORCEPROP 1 LAST TOLERANCE 20%
J 0
(-2250 2175);
DISPLAY 0.617021 (-2250 2175);
PAINT SKYBLUE (-2250 2175);
FORCEPROP 1 LASTPIN (-2350 2300) $PN 1
J 0
(-2340 2280);
DISPLAY 0.617021 (-2340 2280);
PAINT ORANGE (-2340 2280);
FORCEPROP 1 LASTPIN (-2350 2100) $PN 2
J 0
(-2340 2105);
DISPLAY 0.617021 (-2340 2105);
PAINT ORANGE (-2340 2105);
FORCEPROP 1 LAST PACK_TYPE 0805
J 0
(-2250 2125);
DISPLAY 0.617021 (-2250 2125);
PAINT SKYBLUE (-2250 2125);
FORCEPROP 0 LAST GROUP PWR_MCP_CAP
J 0
(-2310 1751);
DISPLAY 0.638298 (-2310 1751);
PAINT BROWN (-2310 1751);
DISPLAY BOTH (-2310 1751);
FORCEPROP 1 LAST PATH I266
J 0
(-2300 2350);
DISPLAY 0.978723 (-2300 2350);
PAINT WHITE (-2300 2350);
DISPLAY INVISIBLE (-2300 2350);
FORCEPROP 0 LAST CDS_SEC 1
J 0
(-2300 2350);
PAINT MONO (-2300 2350);
DISPLAY INVISIBLE (-2300 2350);
FORCEPROP 2 LAST CDS_LIB mstr_discrete
J 0
(-2350 2200);
PAINT MONO (-2350 2200);
DISPLAY INVISIBLE (-2350 2200);
FORCEPROP 2 LAST BOM_COST MEM_VRD_PVDDQ_CD
J 0
(-2300 2350);
PAINT MONO (-2300 2350);
DISPLAY INVISIBLE (-2300 2350);
FORCEPROP 2 LAST ROOM VDDQ_ABC_PWR_VR
J 0
(-2300 2350);
PAINT MONO (-2300 2350);
DISPLAY INVISIBLE (-2300 2350);
FORCEPROP 2 LAST SEC_TYPE 0805
J 0
(-2300 2400);
DISPLAY 1.021277 (-2300 2400);
PAINT ORANGE (-2300 2400);
DISPLAY INVISIBLE (-2300 2400);
FORCEPROP 2 LAST SEC 1
J 0
(-2300 2400);
DISPLAY 0.680851 (-2300 2400);
PAINT MONO (-2300 2400);
DISPLAY INVISIBLE (-2300 2400);
FORCEPROP 1 LAST MATERIAL X5R
J 0
(-2300 2100);
DISPLAY 0.617021 (-2300 2100);
PAINT SKYBLUE (-2300 2100);
DISPLAY INVISIBLE (-2300 2100);
FORCEPROP 2 LAST CDS_LOCATION C7P10
J 0
(-2300 2300);
DISPLAY 0.617021 (-2300 2300);
PAINT AQUA (-2300 2300);
DISPLAY INVISIBLE (-2300 2300);
FORCEADD CAP..1
(-2600 2200);
FORCEPROP 0 LAST NEW_PN 078.1071T.M002
J 0
(-2553 1999);
DISPLAY 0.638298 (-2553 1999);
PAINT BROWN (-2553 1999);
DISPLAY BOTH (-2553 1999);
FORCEPROP 0 LAST NEW_MATERIAL X6S
J 0
(-2550 1950);
DISPLAY 0.638298 (-2550 1950);
PAINT BROWN (-2550 1950);
DISPLAY BOTH (-2550 1950);
FORCEPROP 1 LAST TOLERANCE 20%
J 0
(-2500 2175);
DISPLAY 0.617021 (-2500 2175);
PAINT SKYBLUE (-2500 2175);
FORCEPROP 1 LAST PART_NUMBER 602433-112
R 1
J 0
(-2525 2125);
DISPLAY 0.617021 (-2525 2125);
PAINT BLUE (-2525 2125);
FORCEPROP 1 LAST LOCATION C7P7
J 0
(-2500 2325);
DISPLAY 0.617021 (-2500 2325);
PAINT AQUA (-2500 2325);
FORCEPROP 1 LAST VALUE 100UF
J 0
(-2500 2275);
DISPLAY 0.617021 (-2500 2275);
PAINT SKYBLUE (-2500 2275);
FORCEPROP 1 LAST VOLTAGE 4V
J 0
(-2500 2225);
DISPLAY 0.617021 (-2500 2225);
PAINT SKYBLUE (-2500 2225);
FORCEPROP 1 LASTPIN (-2600 2300) $PN 1
J 0
(-2590 2280);
DISPLAY 0.617021 (-2590 2280);
PAINT ORANGE (-2590 2280);
FORCEPROP 1 LASTPIN (-2600 2100) $PN 2
J 0
(-2590 2105);
DISPLAY 0.617021 (-2590 2105);
PAINT ORANGE (-2590 2105);
FORCEPROP 1 LAST PACK_TYPE 0805
J 0
(-2500 2125);
DISPLAY 0.617021 (-2500 2125);
PAINT SKYBLUE (-2500 2125);
FORCEPROP 0 LAST GROUP PWR_MCP_CAP
J 0
(-2560 1901);
DISPLAY 0.638298 (-2560 1901);
PAINT BROWN (-2560 1901);
DISPLAY BOTH (-2560 1901);
FORCEPROP 1 LAST PATH I267
J 0
(-2550 2350);
DISPLAY 0.978723 (-2550 2350);
PAINT WHITE (-2550 2350);
DISPLAY INVISIBLE (-2550 2350);
FORCEPROP 0 LAST CDS_SEC 1
J 0
(-2550 2350);
PAINT MONO (-2550 2350);
DISPLAY INVISIBLE (-2550 2350);
FORCEPROP 2 LAST CDS_LIB mstr_discrete
J 0
(-2600 2200);
PAINT MONO (-2600 2200);
DISPLAY INVISIBLE (-2600 2200);
FORCEPROP 2 LAST BOM_COST MEM_VRD_PVDDQ_CD
J 0
(-2550 2350);
PAINT MONO (-2550 2350);
DISPLAY INVISIBLE (-2550 2350);
FORCEPROP 2 LAST ROOM VDDQ_ABC_PWR_VR
J 0
(-2550 2350);
PAINT MONO (-2550 2350);
DISPLAY INVISIBLE (-2550 2350);
FORCEPROP 2 LAST SEC_TYPE 0805
J 0
(-2550 2400);
DISPLAY 1.021277 (-2550 2400);
PAINT ORANGE (-2550 2400);
DISPLAY INVISIBLE (-2550 2400);
FORCEPROP 2 LAST SEC 1
J 0
(-2550 2400);
DISPLAY 0.680851 (-2550 2400);
PAINT MONO (-2550 2400);
DISPLAY INVISIBLE (-2550 2400);
FORCEPROP 1 LAST MATERIAL X5R
J 0
(-2550 2100);
DISPLAY 0.617021 (-2550 2100);
PAINT SKYBLUE (-2550 2100);
DISPLAY INVISIBLE (-2550 2100);
FORCEPROP 2 LAST CDS_LOCATION C7P7
J 0
(-2550 2300);
DISPLAY 0.617021 (-2550 2300);
PAINT AQUA (-2550 2300);
DISPLAY INVISIBLE (-2550 2300);
FORCEADD CAP..1
(-1850 2200);
FORCEPROP 0 LAST NEW_MATERIAL X6S
J 0
(-1800 1800);
DISPLAY 0.638298 (-1800 1800);
PAINT BROWN (-1800 1800);
DISPLAY BOTH (-1800 1800);
FORCEPROP 0 LAST NEW_PN 078.1071T.M002
J 0
(-1803 1849);
DISPLAY 0.638298 (-1803 1849);
PAINT BROWN (-1803 1849);
DISPLAY BOTH (-1803 1849);
FORCEPROP 1 LAST VALUE 100UF
J 0
(-1750 2275);
DISPLAY 0.617021 (-1750 2275);
PAINT SKYBLUE (-1750 2275);
FORCEPROP 1 LAST VOLTAGE 4V
J 0
(-1750 2225);
DISPLAY 0.617021 (-1750 2225);
PAINT SKYBLUE (-1750 2225);
FORCEPROP 1 LAST TOLERANCE 20%
J 0
(-1750 2175);
DISPLAY 0.617021 (-1750 2175);
PAINT SKYBLUE (-1750 2175);
FORCEPROP 1 LASTPIN (-1850 2300) $PN 1
J 0
(-1840 2280);
DISPLAY 0.617021 (-1840 2280);
PAINT ORANGE (-1840 2280);
FORCEPROP 1 LAST LOCATION C7P6
J 0
(-1750 2325);
DISPLAY 0.617021 (-1750 2325);
PAINT AQUA (-1750 2325);
FORCEPROP 1 LAST PACK_TYPE 0805
J 0
(-1750 2125);
DISPLAY 0.617021 (-1750 2125);
PAINT SKYBLUE (-1750 2125);
FORCEPROP 1 LASTPIN (-1850 2100) $PN 2
J 0
(-1840 2105);
DISPLAY 0.617021 (-1840 2105);
PAINT ORANGE (-1840 2105);
FORCEPROP 1 LAST PART_NUMBER 602433-112
R 1
J 0
(-1775 2125);
DISPLAY 0.617021 (-1775 2125);
PAINT BLUE (-1775 2125);
FORCEPROP 0 LAST GROUP PWR_MCP_CAP
J 0
(-1810 1751);
DISPLAY 0.638298 (-1810 1751);
PAINT BROWN (-1810 1751);
DISPLAY BOTH (-1810 1751);
FORCEPROP 0 LAST CDS_SEC 1
J 0
(-1800 2350);
PAINT MONO (-1800 2350);
DISPLAY INVISIBLE (-1800 2350);
FORCEPROP 2 LAST CDS_LIB mstr_discrete
J 0
(-1850 2200);
PAINT MONO (-1850 2200);
DISPLAY INVISIBLE (-1850 2200);
FORCEPROP 2 LAST BOM_COST MEM_VRD_PVDDQ_CD
J 0
(-1800 2350);
PAINT MONO (-1800 2350);
DISPLAY INVISIBLE (-1800 2350);
FORCEPROP 2 LAST ROOM VDDQ_ABC_PWR_VR
J 0
(-1800 2350);
PAINT MONO (-1800 2350);
DISPLAY INVISIBLE (-1800 2350);
FORCEPROP 2 LAST SEC_TYPE 0805
J 0
(-1800 2400);
DISPLAY 1.021277 (-1800 2400);
PAINT ORANGE (-1800 2400);
DISPLAY INVISIBLE (-1800 2400);
FORCEPROP 2 LAST SEC 1
J 0
(-1800 2400);
DISPLAY 0.680851 (-1800 2400);
PAINT MONO (-1800 2400);
DISPLAY INVISIBLE (-1800 2400);
FORCEPROP 1 LAST MATERIAL X5R
J 0
(-1800 2100);
DISPLAY 0.617021 (-1800 2100);
PAINT SKYBLUE (-1800 2100);
DISPLAY INVISIBLE (-1800 2100);
FORCEPROP 1 LAST PATH I268
J 0
(-1800 2350);
DISPLAY 0.978723 (-1800 2350);
PAINT WHITE (-1800 2350);
DISPLAY INVISIBLE (-1800 2350);
FORCEPROP 2 LAST CDS_LOCATION C7P6
J 0
(-1800 2300);
DISPLAY 0.617021 (-1800 2300);
PAINT AQUA (-1800 2300);
DISPLAY INVISIBLE (-1800 2300);
FORCEADD CAP..1
(-2100 2200);
FORCEPROP 0 LAST NEW_MATERIAL X6S
J 0
(-2050 1950);
DISPLAY 0.638298 (-2050 1950);
PAINT BROWN (-2050 1950);
DISPLAY BOTH (-2050 1950);
FORCEPROP 0 LAST NEW_PN 078.1071T.M002
J 0
(-2053 1999);
DISPLAY 0.638298 (-2053 1999);
PAINT BROWN (-2053 1999);
DISPLAY BOTH (-2053 1999);
FORCEPROP 1 LAST VALUE 100UF
J 0
(-2000 2275);
DISPLAY 0.617021 (-2000 2275);
PAINT SKYBLUE (-2000 2275);
FORCEPROP 1 LAST VOLTAGE 4V
J 0
(-2000 2225);
DISPLAY 0.617021 (-2000 2225);
PAINT SKYBLUE (-2000 2225);
FORCEPROP 1 LASTPIN (-2100 2300) $PN 1
J 0
(-2090 2280);
DISPLAY 0.617021 (-2090 2280);
PAINT ORANGE (-2090 2280);
FORCEPROP 1 LAST TOLERANCE 20%
J 0
(-2000 2175);
DISPLAY 0.617021 (-2000 2175);
PAINT SKYBLUE (-2000 2175);
FORCEPROP 1 LAST LOCATION C7P13
J 0
(-2000 2325);
DISPLAY 0.617021 (-2000 2325);
PAINT AQUA (-2000 2325);
FORCEPROP 1 LAST PACK_TYPE 0805
J 0
(-2000 2125);
DISPLAY 0.617021 (-2000 2125);
PAINT SKYBLUE (-2000 2125);
FORCEPROP 1 LASTPIN (-2100 2100) $PN 2
J 0
(-2090 2105);
DISPLAY 0.617021 (-2090 2105);
PAINT ORANGE (-2090 2105);
FORCEPROP 1 LAST PART_NUMBER 602433-112
R 1
J 0
(-2025 2125);
DISPLAY 0.617021 (-2025 2125);
PAINT BLUE (-2025 2125);
FORCEPROP 0 LAST GROUP PWR_MCP_CAP
J 0
(-2060 1901);
DISPLAY 0.638298 (-2060 1901);
PAINT BROWN (-2060 1901);
DISPLAY BOTH (-2060 1901);
FORCEPROP 0 LAST CDS_SEC 1
J 0
(-2050 2350);
PAINT MONO (-2050 2350);
DISPLAY INVISIBLE (-2050 2350);
FORCEPROP 2 LAST CDS_LIB mstr_discrete
J 0
(-2100 2200);
PAINT MONO (-2100 2200);
DISPLAY INVISIBLE (-2100 2200);
FORCEPROP 2 LAST BOM_COST MEM_VRD_PVDDQ_CD
J 0
(-2050 2350);
PAINT MONO (-2050 2350);
DISPLAY INVISIBLE (-2050 2350);
FORCEPROP 2 LAST ROOM VDDQ_ABC_PWR_VR
J 0
(-2050 2350);
PAINT MONO (-2050 2350);
DISPLAY INVISIBLE (-2050 2350);
FORCEPROP 2 LAST SEC_TYPE 0805
J 0
(-2050 2400);
DISPLAY 1.021277 (-2050 2400);
PAINT ORANGE (-2050 2400);
DISPLAY INVISIBLE (-2050 2400);
FORCEPROP 2 LAST SEC 1
J 0
(-2050 2400);
DISPLAY 0.680851 (-2050 2400);
PAINT MONO (-2050 2400);
DISPLAY INVISIBLE (-2050 2400);
FORCEPROP 1 LAST MATERIAL X5R
J 0
(-2050 2100);
DISPLAY 0.617021 (-2050 2100);
PAINT SKYBLUE (-2050 2100);
DISPLAY INVISIBLE (-2050 2100);
FORCEPROP 1 LAST PATH I269
J 0
(-2050 2350);
DISPLAY 0.978723 (-2050 2350);
PAINT WHITE (-2050 2350);
DISPLAY INVISIBLE (-2050 2350);
FORCEPROP 2 LAST CDS_LOCATION C7P13
J 0
(-2050 2300);
DISPLAY 0.617021 (-2050 2300);
PAINT AQUA (-2050 2300);
DISPLAY INVISIBLE (-2050 2300);
FORCEADD CAP..1
(-1350 2200);
FORCEPROP 0 LAST NEW_MATERIAL X6S
J 0
(-1300 1800);
DISPLAY 0.638298 (-1300 1800);
PAINT BROWN (-1300 1800);
DISPLAY BOTH (-1300 1800);
FORCEPROP 0 LAST NEW_PN 078.1071T.M002
J 0
(-1303 1849);
DISPLAY 0.638298 (-1303 1849);
PAINT BROWN (-1303 1849);
DISPLAY BOTH (-1303 1849);
FORCEPROP 1 LAST PACK_TYPE 0805
J 0
(-1250 2125);
DISPLAY 0.617021 (-1250 2125);
PAINT SKYBLUE (-1250 2125);
FORCEPROP 1 LAST LOCATION C8P15
J 0
(-1250 2325);
DISPLAY 0.617021 (-1250 2325);
PAINT AQUA (-1250 2325);
FORCEPROP 1 LASTPIN (-1350 2100) $PN 2
J 0
(-1340 2105);
DISPLAY 0.617021 (-1340 2105);
PAINT ORANGE (-1340 2105);
FORCEPROP 1 LASTPIN (-1350 2300) $PN 1
J 0
(-1340 2280);
DISPLAY 0.617021 (-1340 2280);
PAINT ORANGE (-1340 2280);
FORCEPROP 1 LAST TOLERANCE 20%
J 0
(-1250 2175);
DISPLAY 0.617021 (-1250 2175);
PAINT SKYBLUE (-1250 2175);
FORCEPROP 1 LAST VOLTAGE 4V
J 0
(-1250 2225);
DISPLAY 0.617021 (-1250 2225);
PAINT SKYBLUE (-1250 2225);
FORCEPROP 1 LAST VALUE 100UF
J 0
(-1250 2275);
DISPLAY 0.617021 (-1250 2275);
PAINT SKYBLUE (-1250 2275);
FORCEPROP 1 LAST PART_NUMBER 602433-112
R 1
J 0
(-1275 2125);
DISPLAY 0.617021 (-1275 2125);
PAINT BLUE (-1275 2125);
FORCEPROP 0 LAST GROUP PWR_MCP_CAP
J 0
(-1310 1751);
DISPLAY 0.638298 (-1310 1751);
PAINT BROWN (-1310 1751);
DISPLAY BOTH (-1310 1751);
FORCEPROP 1 LAST PATH I270
J 0
(-1300 2350);
DISPLAY 0.978723 (-1300 2350);
PAINT WHITE (-1300 2350);
DISPLAY INVISIBLE (-1300 2350);
FORCEPROP 1 LAST MATERIAL X5R
J 0
(-1300 2100);
DISPLAY 0.617021 (-1300 2100);
PAINT SKYBLUE (-1300 2100);
DISPLAY INVISIBLE (-1300 2100);
FORCEPROP 2 LAST SEC 1
J 0
(-1300 2400);
DISPLAY 0.680851 (-1300 2400);
PAINT MONO (-1300 2400);
DISPLAY INVISIBLE (-1300 2400);
FORCEPROP 2 LAST SEC_TYPE 0805
J 0
(-1300 2400);
DISPLAY 1.021277 (-1300 2400);
PAINT ORANGE (-1300 2400);
DISPLAY INVISIBLE (-1300 2400);
FORCEPROP 2 LAST ROOM VDDQ_ABC_PWR_VR
J 0
(-1300 2350);
PAINT MONO (-1300 2350);
DISPLAY INVISIBLE (-1300 2350);
FORCEPROP 2 LAST BOM_COST MEM_VRD_PVDDQ_CD
J 0
(-1300 2350);
PAINT MONO (-1300 2350);
DISPLAY INVISIBLE (-1300 2350);
FORCEPROP 2 LAST CDS_LIB mstr_discrete
J 0
(-1350 2200);
PAINT MONO (-1350 2200);
DISPLAY INVISIBLE (-1350 2200);
FORCEPROP 0 LAST CDS_SEC 1
J 0
(-1300 2350);
PAINT MONO (-1300 2350);
DISPLAY INVISIBLE (-1300 2350);
FORCEPROP 2 LAST CDS_LOCATION C8P15
J 0
(-1300 2300);
DISPLAY 0.617021 (-1300 2300);
PAINT AQUA (-1300 2300);
DISPLAY INVISIBLE (-1300 2300);
FORCEADD CAP..1
(-1600 2200);
FORCEPROP 0 LAST NEW_PN 078.1071T.M002
J 0
(-1553 1999);
DISPLAY 0.638298 (-1553 1999);
PAINT BROWN (-1553 1999);
DISPLAY BOTH (-1553 1999);
FORCEPROP 1 LAST LOCATION C7P4
J 0
(-1500 2325);
DISPLAY 0.617021 (-1500 2325);
PAINT AQUA (-1500 2325);
FORCEPROP 1 LAST PACK_TYPE 0805
J 0
(-1500 2125);
DISPLAY 0.617021 (-1500 2125);
PAINT SKYBLUE (-1500 2125);
FORCEPROP 1 LAST TOLERANCE 20%
J 0
(-1500 2175);
DISPLAY 0.617021 (-1500 2175);
PAINT SKYBLUE (-1500 2175);
FORCEPROP 1 LAST PART_NUMBER 602433-112
R 1
J 0
(-1525 2125);
DISPLAY 0.617021 (-1525 2125);
PAINT BLUE (-1525 2125);
FORCEPROP 1 LASTPIN (-1600 2100) $PN 2
J 0
(-1590 2105);
DISPLAY 0.617021 (-1590 2105);
PAINT ORANGE (-1590 2105);
FORCEPROP 1 LASTPIN (-1600 2300) $PN 1
J 0
(-1590 2280);
DISPLAY 0.617021 (-1590 2280);
PAINT ORANGE (-1590 2280);
FORCEPROP 1 LAST VOLTAGE 4V
J 0
(-1500 2225);
DISPLAY 0.617021 (-1500 2225);
PAINT SKYBLUE (-1500 2225);
FORCEPROP 1 LAST VALUE 100UF
J 0
(-1500 2275);
DISPLAY 0.617021 (-1500 2275);
PAINT SKYBLUE (-1500 2275);
FORCEPROP 0 LAST NEW_MATERIAL X6S
J 0
(-1550 1950);
DISPLAY 0.638298 (-1550 1950);
PAINT BROWN (-1550 1950);
DISPLAY BOTH (-1550 1950);
FORCEPROP 0 LAST GROUP PWR_MCP_CAP
J 0
(-1560 1901);
DISPLAY 0.638298 (-1560 1901);
PAINT BROWN (-1560 1901);
DISPLAY BOTH (-1560 1901);
FORCEPROP 1 LAST PATH I271
J 0
(-1550 2350);
DISPLAY 0.978723 (-1550 2350);
PAINT WHITE (-1550 2350);
DISPLAY INVISIBLE (-1550 2350);
FORCEPROP 1 LAST MATERIAL X5R
J 0
(-1550 2100);
DISPLAY 0.617021 (-1550 2100);
PAINT SKYBLUE (-1550 2100);
DISPLAY INVISIBLE (-1550 2100);
FORCEPROP 2 LAST SEC 1
J 0
(-1550 2400);
DISPLAY 0.680851 (-1550 2400);
PAINT MONO (-1550 2400);
DISPLAY INVISIBLE (-1550 2400);
FORCEPROP 2 LAST SEC_TYPE 0805
J 0
(-1550 2400);
DISPLAY 1.021277 (-1550 2400);
PAINT ORANGE (-1550 2400);
DISPLAY INVISIBLE (-1550 2400);
FORCEPROP 2 LAST ROOM VDDQ_ABC_PWR_VR
J 0
(-1550 2350);
PAINT MONO (-1550 2350);
DISPLAY INVISIBLE (-1550 2350);
FORCEPROP 2 LAST BOM_COST MEM_VRD_PVDDQ_CD
J 0
(-1550 2350);
PAINT MONO (-1550 2350);
DISPLAY INVISIBLE (-1550 2350);
FORCEPROP 2 LAST CDS_LIB mstr_discrete
J 0
(-1600 2200);
PAINT MONO (-1600 2200);
DISPLAY INVISIBLE (-1600 2200);
FORCEPROP 0 LAST CDS_SEC 1
J 0
(-1550 2350);
PAINT MONO (-1550 2350);
DISPLAY INVISIBLE (-1550 2350);
FORCEPROP 2 LAST CDS_LOCATION C7P4
J 0
(-1550 2300);
DISPLAY 0.617021 (-1550 2300);
PAINT AQUA (-1550 2300);
DISPLAY INVISIBLE (-1550 2300);
FORCEADD CAP..1
(-1100 2200);
FORCEPROP 0 LAST NEW_PN 078.1071T.M002
J 0
(-1053 1999);
DISPLAY 0.638298 (-1053 1999);
PAINT BROWN (-1053 1999);
DISPLAY BOTH (-1053 1999);
FORCEPROP 0 LAST NEW_MATERIAL X6S
J 0
(-1050 1950);
DISPLAY 0.638298 (-1050 1950);
PAINT BROWN (-1050 1950);
DISPLAY BOTH (-1050 1950);
FORCEPROP 1 LAST PACK_TYPE 0805
J 0
(-1000 2125);
DISPLAY 0.617021 (-1000 2125);
PAINT SKYBLUE (-1000 2125);
FORCEPROP 1 LAST VOLTAGE 4V
J 0
(-1000 2225);
DISPLAY 0.617021 (-1000 2225);
PAINT SKYBLUE (-1000 2225);
FORCEPROP 1 LAST LOCATION C8P14
J 0
(-1000 2325);
DISPLAY 0.617021 (-1000 2325);
PAINT AQUA (-1000 2325);
FORCEPROP 1 LAST VALUE 100UF
J 0
(-1000 2275);
DISPLAY 0.617021 (-1000 2275);
PAINT SKYBLUE (-1000 2275);
FORCEPROP 1 LASTPIN (-1100 2300) $PN 1
J 0
(-1090 2280);
DISPLAY 0.617021 (-1090 2280);
PAINT ORANGE (-1090 2280);
FORCEPROP 1 LAST PART_NUMBER 602433-112
R 1
J 0
(-1025 2125);
DISPLAY 0.617021 (-1025 2125);
PAINT BLUE (-1025 2125);
FORCEPROP 1 LAST TOLERANCE 20%
J 0
(-1000 2175);
DISPLAY 0.617021 (-1000 2175);
PAINT SKYBLUE (-1000 2175);
FORCEPROP 1 LASTPIN (-1100 2100) $PN 2
J 0
(-1090 2105);
DISPLAY 0.617021 (-1090 2105);
PAINT ORANGE (-1090 2105);
FORCEPROP 0 LAST GROUP PWR_MCP_CAP
J 0
(-1060 1901);
DISPLAY 0.638298 (-1060 1901);
PAINT BROWN (-1060 1901);
DISPLAY BOTH (-1060 1901);
FORCEPROP 1 LAST PATH I272
J 0
(-1050 2350);
DISPLAY 0.978723 (-1050 2350);
PAINT WHITE (-1050 2350);
DISPLAY INVISIBLE (-1050 2350);
FORCEPROP 0 LAST CDS_SEC 1
J 0
(-1050 2350);
PAINT MONO (-1050 2350);
DISPLAY INVISIBLE (-1050 2350);
FORCEPROP 2 LAST CDS_LIB mstr_discrete
J 0
(-1100 2200);
PAINT MONO (-1100 2200);
DISPLAY INVISIBLE (-1100 2200);
FORCEPROP 2 LAST BOM_COST MEM_VRD_PVDDQ_CD
J 0
(-1050 2350);
PAINT MONO (-1050 2350);
DISPLAY INVISIBLE (-1050 2350);
FORCEPROP 2 LAST ROOM VDDQ_ABC_PWR_VR
J 0
(-1050 2350);
PAINT MONO (-1050 2350);
DISPLAY INVISIBLE (-1050 2350);
FORCEPROP 2 LAST SEC_TYPE 0805
J 0
(-1050 2400);
DISPLAY 1.021277 (-1050 2400);
PAINT ORANGE (-1050 2400);
DISPLAY INVISIBLE (-1050 2400);
FORCEPROP 2 LAST SEC 1
J 0
(-1050 2400);
DISPLAY 0.680851 (-1050 2400);
PAINT MONO (-1050 2400);
DISPLAY INVISIBLE (-1050 2400);
FORCEPROP 1 LAST MATERIAL X5R
J 0
(-1050 2100);
DISPLAY 0.617021 (-1050 2100);
PAINT SKYBLUE (-1050 2100);
DISPLAY INVISIBLE (-1050 2100);
FORCEPROP 2 LAST CDS_LOCATION C8P14
J 0
(-1050 2300);
DISPLAY 0.617021 (-1050 2300);
PAINT AQUA (-1050 2300);
DISPLAY INVISIBLE (-1050 2300);
FORCEADD CAP..1
(-850 2200);
FORCEPROP 0 LAST NEW_PN 078.1071T.M002
J 0
(-803 1849);
DISPLAY 0.638298 (-803 1849);
PAINT BROWN (-803 1849);
DISPLAY BOTH (-803 1849);
FORCEPROP 1 LAST PART_NUMBER 602433-112
R 1
J 0
(-775 2125);
DISPLAY 0.617021 (-775 2125);
PAINT BLUE (-775 2125);
FORCEPROP 1 LAST LOCATION C8P9
J 0
(-750 2325);
DISPLAY 0.617021 (-750 2325);
PAINT AQUA (-750 2325);
FORCEPROP 1 LAST VOLTAGE 4V
J 0
(-750 2225);
DISPLAY 0.617021 (-750 2225);
PAINT SKYBLUE (-750 2225);
FORCEPROP 1 LAST TOLERANCE 20%
J 0
(-750 2175);
DISPLAY 0.617021 (-750 2175);
PAINT SKYBLUE (-750 2175);
FORCEPROP 1 LASTPIN (-850 2300) $PN 1
J 0
(-840 2280);
DISPLAY 0.617021 (-840 2280);
PAINT ORANGE (-840 2280);
FORCEPROP 1 LASTPIN (-850 2100) $PN 2
J 0
(-840 2105);
DISPLAY 0.617021 (-840 2105);
PAINT ORANGE (-840 2105);
FORCEPROP 0 LAST NEW_MATERIAL X6S
J 0
(-800 1800);
DISPLAY 0.638298 (-800 1800);
PAINT BROWN (-800 1800);
DISPLAY BOTH (-800 1800);
FORCEPROP 1 LAST VALUE 100UF
J 0
(-750 2275);
DISPLAY 0.617021 (-750 2275);
PAINT SKYBLUE (-750 2275);
FORCEPROP 1 LAST PACK_TYPE 0805
J 0
(-750 2125);
DISPLAY 0.617021 (-750 2125);
PAINT SKYBLUE (-750 2125);
FORCEPROP 0 LAST GROUP PWR_MCP_CAP
J 0
(-810 1751);
DISPLAY 0.638298 (-810 1751);
PAINT BROWN (-810 1751);
DISPLAY BOTH (-810 1751);
FORCEPROP 1 LAST PATH I273
J 0
(-800 2350);
DISPLAY 0.978723 (-800 2350);
PAINT WHITE (-800 2350);
DISPLAY INVISIBLE (-800 2350);
FORCEPROP 0 LAST CDS_SEC 1
J 0
(-800 2350);
PAINT MONO (-800 2350);
DISPLAY INVISIBLE (-800 2350);
FORCEPROP 2 LAST CDS_LIB mstr_discrete
J 0
(-850 2200);
PAINT MONO (-850 2200);
DISPLAY INVISIBLE (-850 2200);
FORCEPROP 2 LAST BOM_COST MEM_VRD_PVDDQ_CD
J 0
(-800 2350);
PAINT MONO (-800 2350);
DISPLAY INVISIBLE (-800 2350);
FORCEPROP 2 LAST ROOM VDDQ_ABC_PWR_VR
J 0
(-800 2350);
PAINT MONO (-800 2350);
DISPLAY INVISIBLE (-800 2350);
FORCEPROP 2 LAST SEC_TYPE 0805
J 0
(-800 2400);
DISPLAY 1.021277 (-800 2400);
PAINT ORANGE (-800 2400);
DISPLAY INVISIBLE (-800 2400);
FORCEPROP 2 LAST SEC 1
J 0
(-800 2400);
DISPLAY 0.680851 (-800 2400);
PAINT MONO (-800 2400);
DISPLAY INVISIBLE (-800 2400);
FORCEPROP 1 LAST MATERIAL X5R
J 0
(-800 2100);
DISPLAY 0.617021 (-800 2100);
PAINT SKYBLUE (-800 2100);
DISPLAY INVISIBLE (-800 2100);
FORCEPROP 2 LAST CDS_LOCATION C8P9
J 0
(-800 2300);
DISPLAY 0.617021 (-800 2300);
PAINT AQUA (-800 2300);
DISPLAY INVISIBLE (-800 2300);
FORCEADD CAP..1
(-600 2200);
FORCEPROP 1 LAST VALUE 100UF
J 0
(-500 2275);
DISPLAY 0.617021 (-500 2275);
PAINT SKYBLUE (-500 2275);
FORCEPROP 1 LAST TOLERANCE 20%
J 0
(-500 2175);
DISPLAY 0.617021 (-500 2175);
PAINT SKYBLUE (-500 2175);
FORCEPROP 1 LAST PACK_TYPE 0805
J 0
(-500 2125);
DISPLAY 0.617021 (-500 2125);
PAINT SKYBLUE (-500 2125);
FORCEPROP 0 LAST NEW_PN 078.1071T.M002
J 0
(-556 2001);
DISPLAY 0.638298 (-556 2001);
PAINT BROWN (-556 2001);
DISPLAY BOTH (-556 2001);
FORCEPROP 0 LAST NEW_MATERIAL X6S
J 0
(-550 1950);
DISPLAY 0.638298 (-550 1950);
PAINT BROWN (-550 1950);
DISPLAY BOTH (-550 1950);
FORCEPROP 1 LAST LOCATION C8P8
J 0
(-500 2325);
DISPLAY 0.617021 (-500 2325);
PAINT AQUA (-500 2325);
FORCEPROP 1 LAST VOLTAGE 4V
J 0
(-500 2225);
DISPLAY 0.617021 (-500 2225);
PAINT SKYBLUE (-500 2225);
FORCEPROP 1 LAST PART_NUMBER 602433-112
R 1
J 0
(-525 2125);
DISPLAY 0.617021 (-525 2125);
PAINT BLUE (-525 2125);
FORCEPROP 1 LASTPIN (-600 2100) $PN 2
J 0
(-590 2105);
DISPLAY 0.617021 (-590 2105);
PAINT ORANGE (-590 2105);
FORCEPROP 1 LASTPIN (-600 2300) $PN 1
J 0
(-590 2280);
DISPLAY 0.617021 (-590 2280);
PAINT ORANGE (-590 2280);
FORCEPROP 0 LAST GROUP PWR_MCP_CAP
J 0
(-560 1901);
DISPLAY 0.638298 (-560 1901);
PAINT BROWN (-560 1901);
DISPLAY BOTH (-560 1901);
FORCEPROP 1 LAST PATH I274
J 0
(-550 2350);
DISPLAY 0.978723 (-550 2350);
PAINT WHITE (-550 2350);
DISPLAY INVISIBLE (-550 2350);
FORCEPROP 1 LAST MATERIAL X5R
J 0
(-550 2100);
DISPLAY 0.617021 (-550 2100);
PAINT SKYBLUE (-550 2100);
DISPLAY INVISIBLE (-550 2100);
FORCEPROP 2 LAST SEC 1
J 0
(-550 2400);
DISPLAY 0.680851 (-550 2400);
PAINT MONO (-550 2400);
DISPLAY INVISIBLE (-550 2400);
FORCEPROP 2 LAST SEC_TYPE 0805
J 0
(-550 2400);
DISPLAY 1.021277 (-550 2400);
PAINT ORANGE (-550 2400);
DISPLAY INVISIBLE (-550 2400);
FORCEPROP 2 LAST ROOM VDDQ_ABC_PWR_VR
J 0
(-550 2350);
PAINT MONO (-550 2350);
DISPLAY INVISIBLE (-550 2350);
FORCEPROP 2 LAST BOM_COST MEM_VRD_PVDDQ_CD
J 0
(-550 2350);
PAINT MONO (-550 2350);
DISPLAY INVISIBLE (-550 2350);
FORCEPROP 2 LAST CDS_LIB mstr_discrete
J 0
(-600 2200);
PAINT MONO (-600 2200);
DISPLAY INVISIBLE (-600 2200);
FORCEPROP 0 LAST CDS_SEC 1
J 0
(-550 2350);
PAINT MONO (-550 2350);
DISPLAY INVISIBLE (-550 2350);
FORCEPROP 2 LAST CDS_LOCATION C8P8
J 0
(-550 2300);
DISPLAY 0.617021 (-550 2300);
PAINT AQUA (-550 2300);
DISPLAY INVISIBLE (-550 2300);
FORCEADD CAP..1
(-2700 1150);
FORCEPROP 1 LAST LOCATION C7P17
J 0
(-2650 1300);
DISPLAY 0.617021 (-2650 1300);
PAINT AQUA (-2650 1300);
FORCEPROP 0 LAST GROUP PWR_MLCC_CAP
J 0
(-2644 937);
DISPLAY 0.638298 (-2644 937);
PAINT BROWN (-2644 937);
DISPLAY BOTH (-2644 937);
FORCEPROP 1 LAST VOLTAGE 4V
J 0
(-2650 1200);
DISPLAY 0.638298 (-2650 1200);
PAINT SKYBLUE (-2650 1200);
FORCEPROP 1 LAST VALUE 47UF
J 0
(-2650 1250);
DISPLAY 0.617021 (-2650 1250);
PAINT SKYBLUE (-2650 1250);
FORCEPROP 1 LAST PACK_TYPE 0805
J 0
(-2650 1000);
DISPLAY 0.617021 (-2650 1000);
PAINT SKYBLUE (-2650 1000);
FORCEPROP 1 LASTPIN (-2700 1050) $PN 2
J 0
(-2690 1030);
DISPLAY 0.617021 (-2690 1030);
PAINT ORANGE (-2690 1030);
FORCEPROP 1 LASTPIN (-2700 1250) $PN 1
J 0
(-2690 1230);
DISPLAY 0.617021 (-2690 1230);
PAINT ORANGE (-2690 1230);
FORCEPROP 1 LAST TOLERANCE 20%
J 0
(-2650 1150);
DISPLAY 0.617021 (-2650 1150);
PAINT SKYBLUE (-2650 1150);
FORCEPROP 1 LAST PART_NUMBER C95333-006
J 0
(-2650 1050);
DISPLAY 0.617021 (-2650 1050);
PAINT BLUE (-2650 1050);
FORCEPROP 1 LAST MATERIAL X6S
J 0
(-2650 1100);
DISPLAY 0.638298 (-2650 1100);
PAINT SKYBLUE (-2650 1100);
FORCEPROP 2 LAST ROOM PVCCIN_CPU1_DECAP_VR
J 0
(-2650 1250);
PAINT ORANGE (-2650 1250);
DISPLAY INVISIBLE (-2650 1250);
FORCEPROP 1 LAST PATH I29
J 0
(-2650 1300);
DISPLAY 0.978723 (-2650 1300);
PAINT WHITE (-2650 1300);
DISPLAY INVISIBLE (-2650 1300);
FORCEPROP 2 LAST CDS_LOCATION C7P17
J 0
(-2650 1250);
DISPLAY 0.617021 (-2650 1250);
PAINT AQUA (-2650 1250);
DISPLAY INVISIBLE (-2650 1250);
FORCEPROP 2 LAST $SEC 1
J 0
(-2640 1370);
PAINT MONO (-2640 1370);
DISPLAY INVISIBLE (-2640 1370);
FORCEPROP 2 LAST CDS_SEC 1
J 0
(-2640 1370);
PAINT MONO (-2640 1370);
DISPLAY INVISIBLE (-2640 1370);
FORCEPROP 2 LAST CDS_LIB mstr_discrete
J 0
(-2700 1150);
PAINT ORANGE (-2700 1150);
DISPLAY INVISIBLE (-2700 1150);
FORCEPROP 2 LAST BOM_COST PROC
J 0
(-2700 1150);
PAINT MONO (-2700 1150);
DISPLAY INVISIBLE (-2700 1150);
FORCEADD CAP_A..1
(-1600 4450);
FORCEPROP 1 LAST TOLERANCE 20%
J 0
(-1550 4400);
DISPLAY 0.617021 (-1550 4400);
PAINT SKYBLUE (-1550 4400);
FORCEPROP 0 LAST GROUP PWR_MCP_CAP
J 0
(-1550 4150);
DISPLAY 0.638298 (-1550 4150);
PAINT BROWN (-1550 4150);
DISPLAY BOTH (-1550 4150);
FORCEPROP 1 LAST PART_NUMBER E15431-004
J 0
(-1550 4300);
DISPLAY 0.617021 (-1550 4300);
PAINT BLUE (-1550 4300);
FORCEPROP 1 LAST VALUE 22.0UF
J 0
(-1550 4500);
DISPLAY 0.617021 (-1550 4500);
PAINT SKYBLUE (-1550 4500);
FORCEPROP 1 LASTPIN (-1600 4350) $PN 2
J 0
(-1590 4330);
DISPLAY 0.617021 (-1590 4330);
PAINT GREEN (-1590 4330);
FORCEPROP 1 LASTPIN (-1600 4550) $PN 1
J 0
(-1590 4530);
DISPLAY 0.617021 (-1590 4530);
PAINT GREEN (-1590 4530);
FORCEPROP 1 LAST MATERIAL X6S
J 0
(-1550 4350);
DISPLAY 0.617021 (-1550 4350);
PAINT SKYBLUE (-1550 4350);
FORCEPROP 1 LAST VOLTAGE 4V
J 0
(-1550 4450);
DISPLAY 0.617021 (-1550 4450);
PAINT SKYBLUE (-1550 4450);
FORCEPROP 1 LAST PACK_TYPE 0603V
J 0
(-1550 4250);
DISPLAY 0.617021 (-1550 4250);
PAINT SKYBLUE (-1550 4250);
FORCEPROP 1 LAST LOCATION C3D5
J 0
(-1550 4550);
DISPLAY 0.617021 (-1550 4550);
PAINT AQUA (-1550 4550);
FORCEPROP 2 LAST ROOM PVCCIN_CPU1_DECAP_VR
J 0
(-1550 4550);
PAINT ORANGE (-1550 4550);
DISPLAY INVISIBLE (-1550 4550);
FORCEPROP 1 LAST PATH I3
J 0
(-1550 4600);
DISPLAY 0.978723 (-1550 4600);
PAINT WHITE (-1550 4600);
DISPLAY INVISIBLE (-1550 4600);
FORCEPROP 2 LAST $SEC 1
J 0
(-1550 4650);
PAINT MONO (-1550 4650);
DISPLAY INVISIBLE (-1550 4650);
FORCEPROP 2 LAST CDS_SEC 1
J 0
(-1550 4650);
PAINT MONO (-1550 4650);
DISPLAY INVISIBLE (-1550 4650);
FORCEPROP 2 LAST CDS_LIB dev_discrete
J 0
(-1600 4450);
PAINT ORANGE (-1600 4450);
DISPLAY INVISIBLE (-1600 4450);
FORCEPROP 2 LAST BOM_COST PROC
J 0
(-1600 4450);
PAINT MONO (-1600 4450);
DISPLAY INVISIBLE (-1600 4450);
FORCEPROP 2 LAST CDS_LOCATION C3D5
J 0
(-1550 4550);
DISPLAY 0.617021 (-1550 4550);
PAINT AQUA (-1550 4550);
DISPLAY INVISIBLE (-1550 4550);
FORCEADD GND..1
(-3300 775);
FORCEPROP 3 LASTPIN (-3300 825) SIG_NAME GND\g
J 0
(-3290 835);
DISPLAY 0.659574 (-3290 835);
PAINT MONO (-3290 835);
DISPLAY INVISIBLE (-3290 835);
FORCEPROP 1 LAST HDL_POWER GND
J 0
(-3300 925);
DISPLAY 0.893617 (-3300 925);
PAINT GREEN (-3300 925);
DISPLAY INVISIBLE (-3300 925);
FORCEPROP 2 LAST ROOM PVCCIN_CPU1_DECAP_VR
J 0
(-3850 850);
PAINT ORANGE (-3850 850);
DISPLAY INVISIBLE (-3850 850);
FORCEPROP 1 LAST PATH I30
J 0
(-3225 775);
DISPLAY 0.872340 (-3225 775);
PAINT AQUA (-3225 775);
DISPLAY INVISIBLE (-3225 775);
FORCEPROP 1 LAST BODY_TYPE PLUMBING
J 0
(-3345 732);
DISPLAY 0.340426 (-3345 732);
PAINT GREEN (-3345 732);
DISPLAY INVISIBLE (-3345 732);
FORCEPROP 1 LAST SIZE 1B
J 0
(-3225 725);
DISPLAY 0.893617 (-3225 725);
PAINT GREEN (-3225 725);
DISPLAY INVISIBLE (-3225 725);
FORCEPROP 2 LAST CDS_LIB mstr_symbols
J 0
(-3300 775);
PAINT ORANGE (-3300 775);
DISPLAY INVISIBLE (-3300 775);
FORCEPROP 1 LAST VOLTAGE 0
J 0
(-3300 775);
PAINT SKYBLUE (-3300 775);
DISPLAY INVISIBLE (-3300 775);
FORCEADD CAP..1
(-3050 3100);
FORCEPROP 1 LAST LOCATION C2D8
J 0
(-3000 3225);
DISPLAY 0.617021 (-3000 3225);
PAINT AQUA (-3000 3225);
FORCEPROP 0 LAST GROUP PWR_MLCC_CAP
J 0
(-3035 2801);
DISPLAY 0.638298 (-3035 2801);
PAINT BROWN (-3035 2801);
DISPLAY BOTH (-3035 2801);
FORCEPROP 1 LASTPIN (-3050 3000) $PN 2
J 0
(-3040 2980);
DISPLAY 0.617021 (-3040 2980);
PAINT GREEN (-3040 2980);
FORCEPROP 1 LAST VALUE 10UF
J 0
(-3000 3175);
DISPLAY 0.617021 (-3000 3175);
PAINT SKYBLUE (-3000 3175);
FORCEPROP 1 LAST VOLTAGE 4V
J 0
(-3000 3125);
DISPLAY 0.617021 (-3000 3125);
PAINT SKYBLUE (-3000 3125);
FORCEPROP 1 LAST PACK_TYPE 0603LF
J 0
(-3000 2925);
DISPLAY 0.617021 (-3000 2925);
PAINT SKYBLUE (-3000 2925);
FORCEPROP 1 LASTPIN (-3050 3200) $PN 1
J 0
(-3040 3180);
DISPLAY 0.617021 (-3040 3180);
PAINT GREEN (-3040 3180);
FORCEPROP 1 LAST TOLERANCE 20%
J 0
(-3000 3075);
DISPLAY 0.617021 (-3000 3075);
PAINT SKYBLUE (-3000 3075);
FORCEPROP 1 LAST MATERIAL X6S
J 0
(-3000 3025);
DISPLAY 0.617021 (-3000 3025);
PAINT SKYBLUE (-3000 3025);
FORCEPROP 1 LAST PART_NUMBER E15431-001
J 0
(-3000 2975);
DISPLAY 0.617021 (-3000 2975);
PAINT BLUE (-3000 2975);
FORCEPROP 2 LAST ROOM PVCCIN_CPU1_DECAP_VR
J 0
(-3000 3200);
PAINT ORANGE (-3000 3200);
DISPLAY INVISIBLE (-3000 3200);
FORCEPROP 1 LAST PATH I33
J 0
(-3000 3250);
DISPLAY 0.978723 (-3000 3250);
PAINT WHITE (-3000 3250);
DISPLAY INVISIBLE (-3000 3250);
FORCEPROP 2 LAST CDS_LOCATION C2D8
J 0
(-3000 3200);
DISPLAY 0.617021 (-3000 3200);
PAINT AQUA (-3000 3200);
DISPLAY INVISIBLE (-3000 3200);
FORCEPROP 2 LAST $SEC 1
J 0
(-3000 3300);
PAINT MONO (-3000 3300);
DISPLAY INVISIBLE (-3000 3300);
FORCEPROP 2 LAST CDS_SEC 1
J 0
(-3000 3300);
PAINT MONO (-3000 3300);
DISPLAY INVISIBLE (-3000 3300);
FORCEPROP 2 LAST CDS_LIB mstr_discrete
J 0
(-3050 3100);
PAINT ORANGE (-3050 3100);
DISPLAY INVISIBLE (-3050 3100);
FORCEPROP 2 LAST BOM_COST PROC
J 0
(-3050 3100);
PAINT MONO (-3050 3100);
DISPLAY INVISIBLE (-3050 3100);
FORCEADD GND..1
(-3950 2775);
FORCEPROP 3 LASTPIN (-3950 2825) SIG_NAME GND\g
J 0
(-3940 2835);
DISPLAY 0.659574 (-3940 2835);
PAINT MONO (-3940 2835);
DISPLAY INVISIBLE (-3940 2835);
FORCEPROP 1 LAST HDL_POWER GND
J 0
(-3950 2925);
DISPLAY 0.893617 (-3950 2925);
PAINT GREEN (-3950 2925);
DISPLAY INVISIBLE (-3950 2925);
FORCEPROP 2 LAST ROOM PVCCIN_CPU1_DECAP_VR
J 0
(-4500 2850);
PAINT ORANGE (-4500 2850);
DISPLAY INVISIBLE (-4500 2850);
FORCEPROP 1 LAST PATH I36
J 0
(-3875 2775);
DISPLAY 0.872340 (-3875 2775);
PAINT AQUA (-3875 2775);
DISPLAY INVISIBLE (-3875 2775);
FORCEPROP 1 LAST BODY_TYPE PLUMBING
J 0
(-3995 2732);
DISPLAY 0.340426 (-3995 2732);
PAINT GREEN (-3995 2732);
DISPLAY INVISIBLE (-3995 2732);
FORCEPROP 2 LAST CDS_LIB mstr_symbols
J 0
(-3950 2775);
PAINT ORANGE (-3950 2775);
DISPLAY INVISIBLE (-3950 2775);
FORCEPROP 1 LAST SIZE 1B
J 0
(-3875 2725);
DISPLAY 0.893617 (-3875 2725);
PAINT GREEN (-3875 2725);
DISPLAY INVISIBLE (-3875 2725);
FORCEPROP 1 LAST VOLTAGE 0
J 0
(-3950 2775);
PAINT SKYBLUE (-3950 2775);
DISPLAY INVISIBLE (-3950 2775);
FORCEADD CAP..1
(-3350 3100);
FORCEPROP 1 LASTPIN (-3350 3200) $PN 1
J 0
(-3340 3180);
DISPLAY 0.617021 (-3340 3180);
PAINT GREEN (-3340 3180);
FORCEPROP 1 LAST LOCATION C2D10
J 0
(-3300 3225);
DISPLAY 0.617021 (-3300 3225);
PAINT AQUA (-3300 3225);
FORCEPROP 1 LAST MATERIAL X6S
J 0
(-3300 3025);
DISPLAY 0.617021 (-3300 3025);
PAINT SKYBLUE (-3300 3025);
FORCEPROP 1 LAST VOLTAGE 4V
J 0
(-3300 3125);
DISPLAY 0.617021 (-3300 3125);
PAINT SKYBLUE (-3300 3125);
FORCEPROP 1 LASTPIN (-3350 3000) $PN 2
J 0
(-3340 2980);
DISPLAY 0.617021 (-3340 2980);
PAINT GREEN (-3340 2980);
FORCEPROP 1 LAST TOLERANCE 20%
J 0
(-3300 3075);
DISPLAY 0.617021 (-3300 3075);
PAINT SKYBLUE (-3300 3075);
FORCEPROP 1 LAST VALUE 10UF
J 0
(-3300 3175);
DISPLAY 0.617021 (-3300 3175);
PAINT SKYBLUE (-3300 3175);
FORCEPROP 1 LAST PACK_TYPE 0603LF
J 0
(-3300 2925);
DISPLAY 0.617021 (-3300 2925);
PAINT SKYBLUE (-3300 2925);
FORCEPROP 1 LAST PART_NUMBER E15431-001
J 0
(-3300 2975);
DISPLAY 0.617021 (-3300 2975);
PAINT BLUE (-3300 2975);
FORCEPROP 0 LAST GROUP PWR_MLCC_CAP
J 0
(-3310 2876);
DISPLAY 0.638298 (-3310 2876);
PAINT BROWN (-3310 2876);
DISPLAY BOTH (-3310 2876);
FORCEPROP 2 LAST BOM_COST PROC
J 0
(-3350 3100);
PAINT MONO (-3350 3100);
DISPLAY INVISIBLE (-3350 3100);
FORCEPROP 2 LAST CDS_LIB mstr_discrete
J 0
(-3350 3100);
PAINT ORANGE (-3350 3100);
DISPLAY INVISIBLE (-3350 3100);
FORCEPROP 2 LAST CDS_SEC 1
J 0
(-3300 3300);
PAINT MONO (-3300 3300);
DISPLAY INVISIBLE (-3300 3300);
FORCEPROP 2 LAST $SEC 1
J 0
(-3300 3300);
PAINT MONO (-3300 3300);
DISPLAY INVISIBLE (-3300 3300);
FORCEPROP 2 LAST CDS_LOCATION C2D10
J 0
(-3300 3200);
DISPLAY 0.617021 (-3300 3200);
PAINT AQUA (-3300 3200);
DISPLAY INVISIBLE (-3300 3200);
FORCEPROP 1 LAST PATH I37
J 0
(-3300 3250);
DISPLAY 0.978723 (-3300 3250);
PAINT WHITE (-3300 3250);
DISPLAY INVISIBLE (-3300 3250);
FORCEPROP 2 LAST ROOM PVCCIN_CPU1_DECAP_VR
J 0
(-3300 3200);
PAINT ORANGE (-3300 3200);
DISPLAY INVISIBLE (-3300 3200);
FORCEADD CAP_A..1
(-1875 4450);
FORCEPROP 1 LAST MATERIAL X6S
J 0
(-1825 4350);
DISPLAY 0.617021 (-1825 4350);
PAINT SKYBLUE (-1825 4350);
FORCEPROP 1 LASTPIN (-1875 4350) $PN 2
J 0
(-1865 4330);
DISPLAY 0.617021 (-1865 4330);
PAINT GREEN (-1865 4330);
FORCEPROP 0 LAST GROUP PWR_MCP_CAP
J 0
(-1825 4200);
DISPLAY 0.638298 (-1825 4200);
PAINT BROWN (-1825 4200);
DISPLAY BOTH (-1825 4200);
FORCEPROP 1 LAST LOCATION C3D12
J 0
(-1825 4550);
DISPLAY 0.617021 (-1825 4550);
PAINT AQUA (-1825 4550);
FORCEPROP 1 LAST VALUE 22.0UF
J 0
(-1825 4500);
DISPLAY 0.617021 (-1825 4500);
PAINT SKYBLUE (-1825 4500);
FORCEPROP 1 LASTPIN (-1875 4550) $PN 1
J 0
(-1865 4530);
DISPLAY 0.617021 (-1865 4530);
PAINT GREEN (-1865 4530);
FORCEPROP 1 LAST VOLTAGE 4V
J 0
(-1825 4450);
DISPLAY 0.617021 (-1825 4450);
PAINT SKYBLUE (-1825 4450);
FORCEPROP 1 LAST PACK_TYPE 0603V
J 0
(-1825 4250);
DISPLAY 0.617021 (-1825 4250);
PAINT SKYBLUE (-1825 4250);
FORCEPROP 1 LAST TOLERANCE 20%
J 0
(-1825 4400);
DISPLAY 0.617021 (-1825 4400);
PAINT SKYBLUE (-1825 4400);
FORCEPROP 1 LAST PART_NUMBER E15431-004
J 0
(-1825 4300);
DISPLAY 0.617021 (-1825 4300);
PAINT BLUE (-1825 4300);
FORCEPROP 2 LAST ROOM PVCCIN_CPU1_DECAP_VR
J 0
(-1825 4550);
PAINT ORANGE (-1825 4550);
DISPLAY INVISIBLE (-1825 4550);
FORCEPROP 1 LAST PATH I4
J 0
(-1825 4600);
DISPLAY 0.978723 (-1825 4600);
PAINT WHITE (-1825 4600);
DISPLAY INVISIBLE (-1825 4600);
FORCEPROP 2 LAST $SEC 1
J 0
(-1825 4650);
PAINT MONO (-1825 4650);
DISPLAY INVISIBLE (-1825 4650);
FORCEPROP 2 LAST CDS_SEC 1
J 0
(-1825 4650);
PAINT MONO (-1825 4650);
DISPLAY INVISIBLE (-1825 4650);
FORCEPROP 2 LAST CDS_LIB dev_discrete
J 0
(-1875 4450);
PAINT ORANGE (-1875 4450);
DISPLAY INVISIBLE (-1875 4450);
FORCEPROP 2 LAST BOM_COST PROC
J 0
(-1875 4450);
PAINT MONO (-1875 4450);
DISPLAY INVISIBLE (-1875 4450);
FORCEPROP 2 LAST CDS_LOCATION C3D12
J 0
(-1825 4550);
DISPLAY 0.617021 (-1825 4550);
PAINT AQUA (-1825 4550);
DISPLAY INVISIBLE (-1825 4550);
FORCEADD PVSA_CPU1..1
(-3950 3400);
FORCEPROP 3 LASTPIN (-3950 3350) SIG_NAME PVSA_CPU1\g
J 0
(-3940 3360);
DISPLAY 0.659574 (-3940 3360);
PAINT MONO (-3940 3360);
DISPLAY INVISIBLE (-3940 3360);
FORCEPROP 1 LAST HDL_POWER PVSA_CPU1
J 1
(-3950 3450);
DISPLAY 0.872340 (-3950 3450);
PAINT GREEN (-3950 3450);
DISPLAY INVISIBLE (-3950 3450);
FORCEPROP 2 LAST ROOM PVCCIN_CPU1_DECAP_VR
J 0
(-3700 3500);
PAINT ORANGE (-3700 3500);
DISPLAY INVISIBLE (-3700 3500);
FORCEPROP 1 LAST PATH I41
J 0
(-3900 3425);
DISPLAY 0.872340 (-3900 3425);
PAINT AQUA (-3900 3425);
DISPLAY INVISIBLE (-3900 3425);
FORCEPROP 1 LAST BODY_TYPE PLUMBING
J 0
(-3995 3357);
DISPLAY 0.340426 (-3995 3357);
PAINT GREEN (-3995 3357);
DISPLAY INVISIBLE (-3995 3357);
FORCEPROP 2 LAST CDS_LIB mstr_symbols
J 0
(-3950 3400);
PAINT ORANGE (-3950 3400);
DISPLAY INVISIBLE (-3950 3400);
FORCEPROP 1 LAST VOLTAGE 1.1V
J 0
(-3995 3357);
DISPLAY 0.340426 (-3995 3357);
PAINT SKYBLUE (-3995 3357);
DISPLAY INVISIBLE (-3995 3357);
FORCEADD CAP..1
(-3650 3100);
FORCEPROP 1 LAST LOCATION C2D11
J 0
(-3600 3225);
DISPLAY 0.617021 (-3600 3225);
PAINT AQUA (-3600 3225);
FORCEPROP 1 LAST PACK_TYPE 0603LF
J 0
(-3600 2925);
DISPLAY 0.617021 (-3600 2925);
PAINT SKYBLUE (-3600 2925);
FORCEPROP 1 LAST VOLTAGE 4V
J 0
(-3600 3125);
DISPLAY 0.617021 (-3600 3125);
PAINT SKYBLUE (-3600 3125);
FORCEPROP 1 LAST MATERIAL X6S
J 0
(-3600 3025);
DISPLAY 0.617021 (-3600 3025);
PAINT SKYBLUE (-3600 3025);
FORCEPROP 1 LAST PART_NUMBER E15431-001
J 0
(-3600 2975);
DISPLAY 0.617021 (-3600 2975);
PAINT BLUE (-3600 2975);
FORCEPROP 1 LAST TOLERANCE 20%
J 0
(-3600 3075);
DISPLAY 0.617021 (-3600 3075);
PAINT SKYBLUE (-3600 3075);
FORCEPROP 1 LASTPIN (-3650 3000) $PN 2
J 0
(-3640 2980);
DISPLAY 0.617021 (-3640 2980);
PAINT GREEN (-3640 2980);
FORCEPROP 1 LASTPIN (-3650 3200) $PN 1
J 0
(-3640 3180);
DISPLAY 0.617021 (-3640 3180);
PAINT GREEN (-3640 3180);
FORCEPROP 1 LAST VALUE 10UF
J 0
(-3600 3175);
DISPLAY 0.617021 (-3600 3175);
PAINT SKYBLUE (-3600 3175);
FORCEPROP 0 LAST GROUP PWR_MLCC_CAP
J 0
(-3610 2801);
DISPLAY 0.638298 (-3610 2801);
PAINT BROWN (-3610 2801);
DISPLAY BOTH (-3610 2801);
FORCEPROP 2 LAST ROOM PVCCIN_CPU1_DECAP_VR
J 0
(-3600 3200);
PAINT ORANGE (-3600 3200);
DISPLAY INVISIBLE (-3600 3200);
FORCEPROP 1 LAST PATH I42
J 0
(-3600 3250);
DISPLAY 0.978723 (-3600 3250);
PAINT WHITE (-3600 3250);
DISPLAY INVISIBLE (-3600 3250);
FORCEPROP 2 LAST CDS_LOCATION C2D11
J 0
(-3600 3200);
DISPLAY 0.617021 (-3600 3200);
PAINT AQUA (-3600 3200);
DISPLAY INVISIBLE (-3600 3200);
FORCEPROP 2 LAST $SEC 1
J 0
(-3600 3300);
PAINT MONO (-3600 3300);
DISPLAY INVISIBLE (-3600 3300);
FORCEPROP 2 LAST CDS_SEC 1
J 0
(-3600 3300);
PAINT MONO (-3600 3300);
DISPLAY INVISIBLE (-3600 3300);
FORCEPROP 2 LAST BOM_COST PROC
J 0
(-3650 3100);
PAINT MONO (-3650 3100);
DISPLAY INVISIBLE (-3650 3100);
FORCEPROP 2 LAST CDS_LIB mstr_discrete
J 0
(-3650 3100);
PAINT ORANGE (-3650 3100);
DISPLAY INVISIBLE (-3650 3100);
FORCEADD CAP..1
(-3950 3100);
FORCEPROP 1 LAST PART_NUMBER E15431-001
J 0
(-3900 2975);
DISPLAY 0.617021 (-3900 2975);
PAINT BLUE (-3900 2975);
FORCEPROP 1 LAST MATERIAL X6S
J 0
(-3900 3025);
DISPLAY 0.617021 (-3900 3025);
PAINT SKYBLUE (-3900 3025);
FORCEPROP 1 LASTPIN (-3950 3000) $PN 2
J 0
(-3940 2980);
DISPLAY 0.617021 (-3940 2980);
PAINT GREEN (-3940 2980);
FORCEPROP 1 LASTPIN (-3950 3200) $PN 1
J 0
(-3940 3180);
DISPLAY 0.617021 (-3940 3180);
PAINT GREEN (-3940 3180);
FORCEPROP 1 LAST LOCATION C2D9
J 0
(-3900 3225);
DISPLAY 0.617021 (-3900 3225);
PAINT AQUA (-3900 3225);
FORCEPROP 1 LAST TOLERANCE 20%
J 0
(-3900 3075);
DISPLAY 0.617021 (-3900 3075);
PAINT SKYBLUE (-3900 3075);
FORCEPROP 1 LAST VOLTAGE 4V
J 0
(-3900 3125);
DISPLAY 0.617021 (-3900 3125);
PAINT SKYBLUE (-3900 3125);
FORCEPROP 1 LAST VALUE 10UF
J 0
(-3900 3175);
DISPLAY 0.617021 (-3900 3175);
PAINT SKYBLUE (-3900 3175);
FORCEPROP 1 LAST PACK_TYPE 0603LF
J 0
(-3900 2925);
DISPLAY 0.617021 (-3900 2925);
PAINT SKYBLUE (-3900 2925);
FORCEPROP 0 LAST GROUP PWR_MLCC_CAP
J 0
(-3910 2876);
DISPLAY 0.638298 (-3910 2876);
PAINT BROWN (-3910 2876);
DISPLAY BOTH (-3910 2876);
FORCEPROP 2 LAST CDS_LIB mstr_discrete
J 0
(-3950 3100);
PAINT ORANGE (-3950 3100);
DISPLAY INVISIBLE (-3950 3100);
FORCEPROP 2 LAST BOM_COST PROC
J 0
(-3950 3100);
PAINT MONO (-3950 3100);
DISPLAY INVISIBLE (-3950 3100);
FORCEPROP 2 LAST CDS_SEC 1
J 0
(-3900 3300);
PAINT MONO (-3900 3300);
DISPLAY INVISIBLE (-3900 3300);
FORCEPROP 2 LAST $SEC 1
J 0
(-3900 3300);
PAINT MONO (-3900 3300);
DISPLAY INVISIBLE (-3900 3300);
FORCEPROP 2 LAST CDS_LOCATION C2D9
J 0
(-3900 3200);
DISPLAY 0.617021 (-3900 3200);
PAINT AQUA (-3900 3200);
DISPLAY INVISIBLE (-3900 3200);
FORCEPROP 1 LAST PATH I43
J 0
(-3900 3250);
DISPLAY 0.978723 (-3900 3250);
PAINT WHITE (-3900 3250);
DISPLAY INVISIBLE (-3900 3250);
FORCEPROP 2 LAST ROOM PVCCIN_CPU1_DECAP_VR
J 0
(-3900 3200);
PAINT ORANGE (-3900 3200);
DISPLAY INVISIBLE (-3900 3200);
FORCEADD PVCCIO_CPU1..1
(-3300 1450);
FORCEPROP 3 LASTPIN (-3300 1400) SIG_NAME PVCCIO_CPU1\g
J 0
(-3290 1410);
DISPLAY 0.659574 (-3290 1410);
PAINT MONO (-3290 1410);
DISPLAY INVISIBLE (-3290 1410);
FORCEPROP 1 LAST HDL_POWER PVCCIO_CPU1
J 1
(-3300 1500);
DISPLAY 0.872340 (-3300 1500);
PAINT GREEN (-3300 1500);
DISPLAY INVISIBLE (-3300 1500);
FORCEPROP 1 LAST PATH I47
J 0
(-3250 1475);
DISPLAY 0.872340 (-3250 1475);
PAINT AQUA (-3250 1475);
DISPLAY INVISIBLE (-3250 1475);
FORCEPROP 1 LAST BODY_TYPE PLUMBING
J 0
(-3345 1407);
DISPLAY 0.340426 (-3345 1407);
PAINT GREEN (-3345 1407);
DISPLAY INVISIBLE (-3345 1407);
FORCEPROP 2 LAST CDS_LIB mstr_symbols
J 0
(-3300 1450);
PAINT ORANGE (-3300 1450);
DISPLAY INVISIBLE (-3300 1450);
FORCEPROP 1 LAST VOLTAGE 1.1V
J 0
(-3345 1407);
DISPLAY 0.340426 (-3345 1407);
PAINT SKYBLUE (-3345 1407);
DISPLAY INVISIBLE (-3345 1407);
FORCEADD CAP_A..1
(-2175 4450);
FORCEPROP 1 LAST MATERIAL X6S
J 0
(-2125 4350);
DISPLAY 0.617021 (-2125 4350);
PAINT SKYBLUE (-2125 4350);
FORCEPROP 1 LASTPIN (-2175 4350) $PN 2
J 0
(-2165 4330);
DISPLAY 0.617021 (-2165 4330);
PAINT GREEN (-2165 4330);
FORCEPROP 1 LAST LOCATION C3D4
J 0
(-2125 4550);
DISPLAY 0.617021 (-2125 4550);
PAINT AQUA (-2125 4550);
FORCEPROP 1 LAST VALUE 22.0UF
J 0
(-2125 4500);
DISPLAY 0.617021 (-2125 4500);
PAINT SKYBLUE (-2125 4500);
FORCEPROP 1 LAST VOLTAGE 4V
J 0
(-2125 4450);
DISPLAY 0.617021 (-2125 4450);
PAINT SKYBLUE (-2125 4450);
FORCEPROP 1 LAST TOLERANCE 20%
J 0
(-2125 4400);
DISPLAY 0.617021 (-2125 4400);
PAINT SKYBLUE (-2125 4400);
FORCEPROP 1 LAST PART_NUMBER E15431-004
J 0
(-2125 4300);
DISPLAY 0.617021 (-2125 4300);
PAINT BLUE (-2125 4300);
FORCEPROP 1 LAST PACK_TYPE 0603V
J 0
(-2125 4250);
DISPLAY 0.617021 (-2125 4250);
PAINT SKYBLUE (-2125 4250);
FORCEPROP 0 LAST GROUP PWR_MCP_CAP
J 0
(-2125 4150);
DISPLAY 0.638298 (-2125 4150);
PAINT BROWN (-2125 4150);
DISPLAY BOTH (-2125 4150);
FORCEPROP 1 LASTPIN (-2175 4550) $PN 1
J 0
(-2165 4530);
DISPLAY 0.617021 (-2165 4530);
PAINT GREEN (-2165 4530);
FORCEPROP 2 LAST ROOM PVCCIN_CPU1_DECAP_VR
J 0
(-2125 4550);
PAINT ORANGE (-2125 4550);
DISPLAY INVISIBLE (-2125 4550);
FORCEPROP 1 LAST PATH I5
J 0
(-2125 4600);
DISPLAY 0.978723 (-2125 4600);
PAINT WHITE (-2125 4600);
DISPLAY INVISIBLE (-2125 4600);
FORCEPROP 2 LAST $SEC 1
J 0
(-2125 4650);
PAINT MONO (-2125 4650);
DISPLAY INVISIBLE (-2125 4650);
FORCEPROP 2 LAST CDS_SEC 1
J 0
(-2125 4650);
PAINT MONO (-2125 4650);
DISPLAY INVISIBLE (-2125 4650);
FORCEPROP 2 LAST CDS_LIB dev_discrete
J 0
(-2175 4450);
PAINT ORANGE (-2175 4450);
DISPLAY INVISIBLE (-2175 4450);
FORCEPROP 2 LAST BOM_COST PROC
J 0
(-2175 4450);
PAINT MONO (-2175 4450);
DISPLAY INVISIBLE (-2175 4450);
FORCEPROP 2 LAST CDS_LOCATION C3D4
J 0
(-2125 4550);
DISPLAY 0.617021 (-2125 4550);
PAINT AQUA (-2125 4550);
DISPLAY INVISIBLE (-2125 4550);
FORCEADD CAP..1
(-3000 1150);
FORCEPROP 1 LAST PART_NUMBER C95333-006
J 0
(-2950 1050);
DISPLAY 0.617021 (-2950 1050);
PAINT BLUE (-2950 1050);
FORCEPROP 1 LAST LOCATION C7P18
J 0
(-2950 1300);
DISPLAY 0.617021 (-2950 1300);
PAINT AQUA (-2950 1300);
FORCEPROP 1 LASTPIN (-3000 1250) $PN 1
J 0
(-2990 1230);
DISPLAY 0.617021 (-2990 1230);
PAINT ORANGE (-2990 1230);
FORCEPROP 1 LAST PACK_TYPE 0805
J 0
(-2950 1000);
DISPLAY 0.617021 (-2950 1000);
PAINT SKYBLUE (-2950 1000);
FORCEPROP 1 LAST MATERIAL X6S
J 0
(-2950 1100);
DISPLAY 0.638298 (-2950 1100);
PAINT SKYBLUE (-2950 1100);
FORCEPROP 1 LAST TOLERANCE 20%
J 0
(-2950 1150);
DISPLAY 0.617021 (-2950 1150);
PAINT SKYBLUE (-2950 1150);
FORCEPROP 1 LASTPIN (-3000 1050) $PN 2
J 0
(-2990 1030);
DISPLAY 0.617021 (-2990 1030);
PAINT ORANGE (-2990 1030);
FORCEPROP 1 LAST VOLTAGE 4V
J 0
(-2950 1200);
DISPLAY 0.638298 (-2950 1200);
PAINT SKYBLUE (-2950 1200);
FORCEPROP 1 LAST VALUE 47UF
J 0
(-2950 1250);
DISPLAY 0.617021 (-2950 1250);
PAINT SKYBLUE (-2950 1250);
FORCEPROP 0 LAST GROUP PWR_MLCC_CAP
J 0
(-2944 887);
DISPLAY 0.638298 (-2944 887);
PAINT BROWN (-2944 887);
DISPLAY BOTH (-2944 887);
FORCEPROP 2 LAST ROOM PVCCIN_CPU1_DECAP_VR
J 0
(-2925 1250);
PAINT ORANGE (-2925 1250);
DISPLAY INVISIBLE (-2925 1250);
FORCEPROP 1 LAST PATH I51
J 0
(-2950 1300);
DISPLAY 0.978723 (-2950 1300);
PAINT WHITE (-2950 1300);
DISPLAY INVISIBLE (-2950 1300);
FORCEPROP 2 LAST CDS_LOCATION C7P18
J 0
(-2950 1250);
DISPLAY 0.617021 (-2950 1250);
PAINT AQUA (-2950 1250);
DISPLAY INVISIBLE (-2950 1250);
FORCEPROP 2 LAST $SEC 1
J 0
(-2940 1370);
PAINT MONO (-2940 1370);
DISPLAY INVISIBLE (-2940 1370);
FORCEPROP 2 LAST CDS_SEC 1
J 0
(-2940 1370);
PAINT MONO (-2940 1370);
DISPLAY INVISIBLE (-2940 1370);
FORCEPROP 2 LAST CDS_LIB mstr_discrete
J 0
(-3000 1150);
PAINT ORANGE (-3000 1150);
DISPLAY INVISIBLE (-3000 1150);
FORCEPROP 2 LAST BOM_COST PROC
J 0
(-3000 1150);
PAINT MONO (-3000 1150);
DISPLAY INVISIBLE (-3000 1150);
FORCEADD CAP..1
(-3300 1150);
FORCEPROP 1 LAST LOCATION C7P3
J 0
(-3250 1300);
DISPLAY 0.617021 (-3250 1300);
PAINT AQUA (-3250 1300);
FORCEPROP 1 LAST VALUE 47UF
J 0
(-3250 1250);
DISPLAY 0.617021 (-3250 1250);
PAINT SKYBLUE (-3250 1250);
FORCEPROP 0 LAST GROUP PWR_MLCC_CAP
J 0
(-3244 937);
DISPLAY 0.638298 (-3244 937);
PAINT BROWN (-3244 937);
DISPLAY BOTH (-3244 937);
FORCEPROP 1 LAST VOLTAGE 4V
J 0
(-3250 1200);
DISPLAY 0.638298 (-3250 1200);
PAINT SKYBLUE (-3250 1200);
FORCEPROP 1 LASTPIN (-3300 1250) $PN 1
J 0
(-3290 1230);
DISPLAY 0.617021 (-3290 1230);
PAINT ORANGE (-3290 1230);
FORCEPROP 1 LAST PART_NUMBER C95333-006
J 0
(-3250 1050);
DISPLAY 0.617021 (-3250 1050);
PAINT BLUE (-3250 1050);
FORCEPROP 1 LAST PACK_TYPE 0805
J 0
(-3250 1000);
DISPLAY 0.617021 (-3250 1000);
PAINT SKYBLUE (-3250 1000);
FORCEPROP 1 LAST MATERIAL X6S
J 0
(-3250 1100);
DISPLAY 0.638298 (-3250 1100);
PAINT SKYBLUE (-3250 1100);
FORCEPROP 1 LASTPIN (-3300 1050) $PN 2
J 0
(-3290 1030);
DISPLAY 0.617021 (-3290 1030);
PAINT ORANGE (-3290 1030);
FORCEPROP 1 LAST TOLERANCE 20%
J 0
(-3250 1150);
DISPLAY 0.617021 (-3250 1150);
PAINT SKYBLUE (-3250 1150);
FORCEPROP 2 LAST ROOM PVCCIN_CPU1_DECAP_VR
J 0
(-3250 1250);
PAINT ORANGE (-3250 1250);
DISPLAY INVISIBLE (-3250 1250);
FORCEPROP 1 LAST PATH I52
J 0
(-3250 1300);
DISPLAY 0.978723 (-3250 1300);
PAINT WHITE (-3250 1300);
DISPLAY INVISIBLE (-3250 1300);
FORCEPROP 2 LAST CDS_LOCATION C7P3
J 0
(-3250 1250);
DISPLAY 0.617021 (-3250 1250);
PAINT AQUA (-3250 1250);
DISPLAY INVISIBLE (-3250 1250);
FORCEPROP 2 LAST $SEC 1
J 0
(-3240 1370);
PAINT MONO (-3240 1370);
DISPLAY INVISIBLE (-3240 1370);
FORCEPROP 2 LAST CDS_SEC 1
J 0
(-3240 1370);
PAINT MONO (-3240 1370);
DISPLAY INVISIBLE (-3240 1370);
FORCEPROP 2 LAST CDS_LIB mstr_discrete
J 0
(-3300 1150);
PAINT ORANGE (-3300 1150);
DISPLAY INVISIBLE (-3300 1150);
FORCEPROP 2 LAST BOM_COST PROC
J 0
(-3300 1150);
PAINT MONO (-3300 1150);
DISPLAY INVISIBLE (-3300 1150);
FORCEADD GND..1
(-3950 775);
FORCEPROP 3 LASTPIN (-3950 825) SIG_NAME GND\g
J 0
(-3940 835);
DISPLAY 0.659574 (-3940 835);
PAINT MONO (-3940 835);
DISPLAY INVISIBLE (-3940 835);
FORCEPROP 1 LAST HDL_POWER GND
J 0
(-3950 925);
DISPLAY 0.893617 (-3950 925);
PAINT GREEN (-3950 925);
DISPLAY INVISIBLE (-3950 925);
FORCEPROP 2 LAST ROOM PVCCIN_CPU1_DECAP_VR
J 0
(-4500 850);
PAINT ORANGE (-4500 850);
DISPLAY INVISIBLE (-4500 850);
FORCEPROP 1 LAST PATH I53
J 0
(-3875 775);
DISPLAY 0.872340 (-3875 775);
PAINT AQUA (-3875 775);
DISPLAY INVISIBLE (-3875 775);
FORCEPROP 1 LAST BODY_TYPE PLUMBING
J 0
(-3995 732);
DISPLAY 0.340426 (-3995 732);
PAINT GREEN (-3995 732);
DISPLAY INVISIBLE (-3995 732);
FORCEPROP 1 LAST SIZE 1B
J 0
(-3875 725);
DISPLAY 0.893617 (-3875 725);
PAINT GREEN (-3875 725);
DISPLAY INVISIBLE (-3875 725);
FORCEPROP 2 LAST CDS_LIB mstr_symbols
J 0
(-3950 775);
PAINT MONO (-3950 775);
DISPLAY INVISIBLE (-3950 775);
FORCEPROP 1 LAST VOLTAGE 0
J 0
(-3950 775);
PAINT SKYBLUE (-3950 775);
DISPLAY INVISIBLE (-3950 775);
FORCEADD PVSA_CPU1..1
(-4550 1450);
FORCEPROP 3 LASTPIN (-4550 1400) SIG_NAME PVSA_CPU1\g
J 0
(-4540 1410);
DISPLAY 0.659574 (-4540 1410);
PAINT MONO (-4540 1410);
DISPLAY INVISIBLE (-4540 1410);
FORCEPROP 1 LAST VOLTAGE 1.1V
J 0
(-4595 1407);
DISPLAY 0.340426 (-4595 1407);
PAINT SKYBLUE (-4595 1407);
DISPLAY INVISIBLE (-4595 1407);
FORCEPROP 2 LAST CDS_LIB mstr_symbols
J 0
(-4550 1450);
PAINT ORANGE (-4550 1450);
DISPLAY INVISIBLE (-4550 1450);
FORCEPROP 1 LAST BODY_TYPE PLUMBING
J 0
(-4595 1407);
DISPLAY 0.340426 (-4595 1407);
PAINT GREEN (-4595 1407);
DISPLAY INVISIBLE (-4595 1407);
FORCEPROP 1 LAST PATH I57
J 0
(-4500 1475);
DISPLAY 0.872340 (-4500 1475);
PAINT AQUA (-4500 1475);
DISPLAY INVISIBLE (-4500 1475);
FORCEPROP 1 LAST HDL_POWER PVSA_CPU1
J 1
(-4550 1500);
DISPLAY 0.872340 (-4550 1500);
PAINT GREEN (-4550 1500);
DISPLAY INVISIBLE (-4550 1500);
FORCEADD CAP_A..1
(-4800 4450);
FORCEPROP 0 LAST GROUP PWR_MLCC_CAP
J 0
(-4744 4212);
DISPLAY 0.638298 (-4744 4212);
PAINT BROWN (-4744 4212);
DISPLAY BOTH (-4744 4212);
FORCEPROP 1 LAST MATERIAL X6S
J 0
(-4750 4400);
DISPLAY 0.617021 (-4750 4400);
PAINT SKYBLUE (-4750 4400);
FORCEPROP 1 LAST TOLERANCE 20%
J 0
(-4750 4450);
DISPLAY 0.617021 (-4750 4450);
PAINT SKYBLUE (-4750 4450);
FORCEPROP 1 LASTPIN (-4800 4550) $PN 1
J 0
(-4790 4530);
DISPLAY 0.617021 (-4790 4530);
PAINT GREEN (-4790 4530);
FORCEPROP 1 LASTPIN (-4800 4350) $PN 2
J 0
(-4790 4330);
DISPLAY 0.617021 (-4790 4330);
PAINT GREEN (-4790 4330);
FORCEPROP 1 LAST LOCATION C2D12
J 0
(-4750 4600);
DISPLAY 0.617021 (-4750 4600);
PAINT AQUA (-4750 4600);
FORCEPROP 1 LAST VALUE 22.0UF
J 0
(-4750 4550);
DISPLAY 0.617021 (-4750 4550);
PAINT SKYBLUE (-4750 4550);
FORCEPROP 1 LAST VOLTAGE 4V
J 0
(-4750 4500);
DISPLAY 0.617021 (-4750 4500);
PAINT SKYBLUE (-4750 4500);
FORCEPROP 1 LAST PART_NUMBER E15431-004
J 0
(-4750 4350);
DISPLAY 0.617021 (-4750 4350);
PAINT BLUE (-4750 4350);
FORCEPROP 1 LAST PACK_TYPE 0603V
J 0
(-4750 4300);
DISPLAY 0.617021 (-4750 4300);
PAINT SKYBLUE (-4750 4300);
FORCEPROP 2 LAST CDS_LOCATION C2D12
J 0
(-4750 4550);
DISPLAY 0.617021 (-4750 4550);
PAINT AQUA (-4750 4550);
DISPLAY INVISIBLE (-4750 4550);
FORCEPROP 2 LAST BOM_COST PROC
J 0
(-4800 4450);
PAINT MONO (-4800 4450);
DISPLAY INVISIBLE (-4800 4450);
FORCEPROP 2 LAST CDS_LIB dev_discrete
J 0
(-4800 4450);
PAINT ORANGE (-4800 4450);
DISPLAY INVISIBLE (-4800 4450);
FORCEPROP 2 LAST CDS_SEC 1
J 0
(-4750 4650);
PAINT MONO (-4750 4650);
DISPLAY INVISIBLE (-4750 4650);
FORCEPROP 2 LAST $SEC 1
J 0
(-4750 4650);
PAINT MONO (-4750 4650);
DISPLAY INVISIBLE (-4750 4650);
FORCEPROP 1 LAST PATH I59
J 0
(-4750 4600);
DISPLAY 0.978723 (-4750 4600);
PAINT WHITE (-4750 4600);
DISPLAY INVISIBLE (-4750 4600);
FORCEPROP 2 LAST ROOM PVCCIN_CPU1_DECAP_VR
J 0
(-4750 4550);
PAINT ORANGE (-4750 4550);
DISPLAY INVISIBLE (-4750 4550);
FORCEADD GND..1
(-5900 4175);
FORCEPROP 3 LASTPIN (-5900 4225) SIG_NAME GND\g
J 0
(-5890 4235);
DISPLAY 0.659574 (-5890 4235);
PAINT MONO (-5890 4235);
DISPLAY INVISIBLE (-5890 4235);
FORCEPROP 1 LAST VOLTAGE 0
J 0
(-5900 4175);
PAINT SKYBLUE (-5900 4175);
DISPLAY INVISIBLE (-5900 4175);
FORCEPROP 2 LAST CDS_LIB mstr_symbols
J 0
(-5900 4175);
PAINT ORANGE (-5900 4175);
DISPLAY INVISIBLE (-5900 4175);
FORCEPROP 1 LAST SIZE 1B
J 0
(-5825 4125);
DISPLAY 0.893617 (-5825 4125);
PAINT GREEN (-5825 4125);
DISPLAY INVISIBLE (-5825 4125);
FORCEPROP 1 LAST BODY_TYPE PLUMBING
J 0
(-5945 4132);
DISPLAY 0.340426 (-5945 4132);
PAINT GREEN (-5945 4132);
DISPLAY INVISIBLE (-5945 4132);
FORCEPROP 1 LAST PATH I60
J 0
(-5825 4175);
DISPLAY 0.872340 (-5825 4175);
PAINT AQUA (-5825 4175);
DISPLAY INVISIBLE (-5825 4175);
FORCEPROP 2 LAST ROOM PVCCIN_CPU1_DECAP_VR
J 0
(-6450 4250);
PAINT ORANGE (-6450 4250);
DISPLAY INVISIBLE (-6450 4250);
FORCEPROP 1 LAST HDL_POWER GND
J 0
(-5900 4325);
DISPLAY 0.893617 (-5900 4325);
PAINT GREEN (-5900 4325);
DISPLAY INVISIBLE (-5900 4325);
FORCEADD CAP_A..1
(-5100 4450);
FORCEPROP 1 LAST PART_NUMBER E15431-004
J 0
(-5050 4350);
DISPLAY 0.617021 (-5050 4350);
PAINT BLUE (-5050 4350);
FORCEPROP 1 LAST TOLERANCE 20%
J 0
(-5050 4450);
DISPLAY 0.617021 (-5050 4450);
PAINT SKYBLUE (-5050 4450);
FORCEPROP 1 LASTPIN (-5100 4350) $PN 2
J 0
(-5090 4330);
DISPLAY 0.617021 (-5090 4330);
PAINT GREEN (-5090 4330);
FORCEPROP 1 LAST PACK_TYPE 0603V
J 0
(-5050 4300);
DISPLAY 0.617021 (-5050 4300);
PAINT SKYBLUE (-5050 4300);
FORCEPROP 1 LAST VOLTAGE 4V
J 0
(-5050 4500);
DISPLAY 0.617021 (-5050 4500);
PAINT SKYBLUE (-5050 4500);
FORCEPROP 1 LAST VALUE 22.0UF
J 0
(-5050 4550);
DISPLAY 0.617021 (-5050 4550);
PAINT SKYBLUE (-5050 4550);
FORCEPROP 1 LAST LOCATION C2D22
J 0
(-5050 4600);
DISPLAY 0.617021 (-5050 4600);
PAINT AQUA (-5050 4600);
FORCEPROP 1 LASTPIN (-5100 4550) $PN 1
J 0
(-5090 4530);
DISPLAY 0.617021 (-5090 4530);
PAINT GREEN (-5090 4530);
FORCEPROP 1 LAST MATERIAL X6S
J 0
(-5050 4400);
DISPLAY 0.617021 (-5050 4400);
PAINT SKYBLUE (-5050 4400);
FORCEPROP 0 LAST GROUP PWR_MLCC_CAP
J 0
(-5044 4262);
DISPLAY 0.638298 (-5044 4262);
PAINT BROWN (-5044 4262);
DISPLAY BOTH (-5044 4262);
FORCEPROP 2 LAST CDS_LOCATION C2D22
J 0
(-5050 4550);
DISPLAY 0.617021 (-5050 4550);
PAINT AQUA (-5050 4550);
DISPLAY INVISIBLE (-5050 4550);
FORCEPROP 2 LAST BOM_COST PROC
J 0
(-5100 4450);
PAINT MONO (-5100 4450);
DISPLAY INVISIBLE (-5100 4450);
FORCEPROP 2 LAST CDS_LIB dev_discrete
J 0
(-5100 4450);
PAINT ORANGE (-5100 4450);
DISPLAY INVISIBLE (-5100 4450);
FORCEPROP 2 LAST CDS_SEC 1
J 0
(-5050 4650);
PAINT MONO (-5050 4650);
DISPLAY INVISIBLE (-5050 4650);
FORCEPROP 2 LAST $SEC 1
J 0
(-5050 4650);
PAINT MONO (-5050 4650);
DISPLAY INVISIBLE (-5050 4650);
FORCEPROP 1 LAST PATH I61
J 0
(-5050 4600);
DISPLAY 0.978723 (-5050 4600);
PAINT WHITE (-5050 4600);
DISPLAY INVISIBLE (-5050 4600);
FORCEPROP 2 LAST ROOM PVCCIN_CPU1_DECAP_VR
J 0
(-5050 4550);
PAINT ORANGE (-5050 4550);
DISPLAY INVISIBLE (-5050 4550);
FORCEADD CAP_A..1
(-5600 4450);
FORCEPROP 0 LAST GROUP PWR_MLCC_CAP
J 0
(-5544 4212);
DISPLAY 0.638298 (-5544 4212);
PAINT BROWN (-5544 4212);
DISPLAY BOTH (-5544 4212);
FORCEPROP 1 LAST MATERIAL X6S
J 0
(-5550 4400);
DISPLAY 0.617021 (-5550 4400);
PAINT SKYBLUE (-5550 4400);
FORCEPROP 1 LAST TOLERANCE 20%
J 0
(-5550 4450);
DISPLAY 0.617021 (-5550 4450);
PAINT SKYBLUE (-5550 4450);
FORCEPROP 1 LAST PART_NUMBER E15431-004
J 0
(-5550 4350);
DISPLAY 0.617021 (-5550 4350);
PAINT BLUE (-5550 4350);
FORCEPROP 1 LAST VALUE 22.0UF
J 0
(-5550 4550);
DISPLAY 0.617021 (-5550 4550);
PAINT SKYBLUE (-5550 4550);
FORCEPROP 1 LAST LOCATION C2D31
J 0
(-5550 4600);
DISPLAY 0.617021 (-5550 4600);
PAINT AQUA (-5550 4600);
FORCEPROP 1 LAST VOLTAGE 4V
J 0
(-5550 4500);
DISPLAY 0.617021 (-5550 4500);
PAINT SKYBLUE (-5550 4500);
FORCEPROP 1 LAST PACK_TYPE 0603V
J 0
(-5550 4300);
DISPLAY 0.617021 (-5550 4300);
PAINT SKYBLUE (-5550 4300);
FORCEPROP 1 LASTPIN (-5600 4350) $PN 2
J 0
(-5590 4330);
DISPLAY 0.617021 (-5590 4330);
PAINT GREEN (-5590 4330);
FORCEPROP 1 LASTPIN (-5600 4550) $PN 1
J 0
(-5590 4530);
DISPLAY 0.617021 (-5590 4530);
PAINT GREEN (-5590 4530);
FORCEPROP 2 LAST ROOM PVCCIN_CPU1_DECAP_VR
J 0
(-5550 4550);
PAINT ORANGE (-5550 4550);
DISPLAY INVISIBLE (-5550 4550);
FORCEPROP 1 LAST PATH I63
J 0
(-5550 4600);
DISPLAY 0.978723 (-5550 4600);
PAINT WHITE (-5550 4600);
DISPLAY INVISIBLE (-5550 4600);
FORCEPROP 2 LAST $SEC 1
J 0
(-5550 4650);
PAINT MONO (-5550 4650);
DISPLAY INVISIBLE (-5550 4650);
FORCEPROP 2 LAST CDS_SEC 1
J 0
(-5550 4650);
PAINT MONO (-5550 4650);
DISPLAY INVISIBLE (-5550 4650);
FORCEPROP 2 LAST CDS_LIB dev_discrete
J 0
(-5600 4450);
PAINT ORANGE (-5600 4450);
DISPLAY INVISIBLE (-5600 4450);
FORCEPROP 2 LAST BOM_COST PROC
J 0
(-5600 4450);
PAINT MONO (-5600 4450);
DISPLAY INVISIBLE (-5600 4450);
FORCEPROP 2 LAST CDS_LOCATION C2D31
J 0
(-5550 4550);
DISPLAY 0.617021 (-5550 4550);
PAINT AQUA (-5550 4550);
DISPLAY INVISIBLE (-5550 4550);
FORCEADD CAP_A..1
(-5900 4450);
FORCEPROP 0 LAST GROUP PWR_MLCC_CAP
J 0
(-5844 4262);
DISPLAY 0.638298 (-5844 4262);
PAINT BROWN (-5844 4262);
DISPLAY BOTH (-5844 4262);
FORCEPROP 1 LASTPIN (-5900 4550) $PN 1
J 0
(-5890 4530);
DISPLAY 0.617021 (-5890 4530);
PAINT GREEN (-5890 4530);
FORCEPROP 1 LAST VOLTAGE 4V
J 0
(-5850 4500);
DISPLAY 0.617021 (-5850 4500);
PAINT SKYBLUE (-5850 4500);
FORCEPROP 1 LAST PACK_TYPE 0603V
J 0
(-5850 4300);
DISPLAY 0.617021 (-5850 4300);
PAINT SKYBLUE (-5850 4300);
FORCEPROP 1 LAST LOCATION C2D21
J 0
(-5850 4600);
DISPLAY 0.617021 (-5850 4600);
PAINT AQUA (-5850 4600);
FORCEPROP 1 LAST VALUE 22.0UF
J 0
(-5850 4550);
DISPLAY 0.617021 (-5850 4550);
PAINT SKYBLUE (-5850 4550);
FORCEPROP 1 LAST TOLERANCE 20%
J 0
(-5850 4450);
DISPLAY 0.617021 (-5850 4450);
PAINT SKYBLUE (-5850 4450);
FORCEPROP 1 LAST MATERIAL X6S
J 0
(-5850 4400);
DISPLAY 0.617021 (-5850 4400);
PAINT SKYBLUE (-5850 4400);
FORCEPROP 1 LAST PART_NUMBER E15431-004
J 0
(-5850 4350);
DISPLAY 0.617021 (-5850 4350);
PAINT BLUE (-5850 4350);
FORCEPROP 1 LASTPIN (-5900 4350) $PN 2
J 0
(-5890 4330);
DISPLAY 0.617021 (-5890 4330);
PAINT GREEN (-5890 4330);
FORCEPROP 2 LAST ROOM PVCCIN_CPU1_DECAP_VR
J 0
(-5850 4550);
PAINT ORANGE (-5850 4550);
DISPLAY INVISIBLE (-5850 4550);
FORCEPROP 1 LAST PATH I65
J 0
(-5850 4600);
DISPLAY 0.978723 (-5850 4600);
PAINT WHITE (-5850 4600);
DISPLAY INVISIBLE (-5850 4600);
FORCEPROP 2 LAST $SEC 1
J 0
(-5850 4650);
PAINT MONO (-5850 4650);
DISPLAY INVISIBLE (-5850 4650);
FORCEPROP 2 LAST CDS_SEC 1
J 0
(-5850 4650);
PAINT MONO (-5850 4650);
DISPLAY INVISIBLE (-5850 4650);
FORCEPROP 2 LAST CDS_LIB dev_discrete
J 0
(-5900 4450);
PAINT ORANGE (-5900 4450);
DISPLAY INVISIBLE (-5900 4450);
FORCEPROP 2 LAST BOM_COST PROC
J 0
(-5900 4450);
PAINT MONO (-5900 4450);
DISPLAY INVISIBLE (-5900 4450);
FORCEPROP 2 LAST CDS_LOCATION C2D21
J 0
(-5850 4550);
DISPLAY 0.617021 (-5850 4550);
PAINT AQUA (-5850 4550);
DISPLAY INVISIBLE (-5850 4550);
FORCEADD CAP_A..1
(-6650 4450);
FORCEPROP 1 LAST TOLERANCE 20%
J 0
(-6600 4450);
DISPLAY 0.617021 (-6600 4450);
PAINT SKYBLUE (-6600 4450);
FORCEPROP 1 LAST PART_NUMBER E15431-004
J 0
(-6600 4350);
DISPLAY 0.617021 (-6600 4350);
PAINT BLUE (-6600 4350);
FORCEPROP 1 LASTPIN (-6650 4350) $PN 2
J 0
(-6640 4330);
DISPLAY 0.617021 (-6640 4330);
PAINT GREEN (-6640 4330);
FORCEPROP 1 LAST PACK_TYPE 0603V
J 0
(-6600 4300);
DISPLAY 0.617021 (-6600 4300);
PAINT SKYBLUE (-6600 4300);
FORCEPROP 0 LAST GROUP PWR_MLCC_CAP
J 0
(-6594 4262);
DISPLAY 0.638298 (-6594 4262);
PAINT BROWN (-6594 4262);
DISPLAY BOTH (-6594 4262);
FORCEPROP 1 LAST MATERIAL X6S
J 0
(-6600 4400);
DISPLAY 0.617021 (-6600 4400);
PAINT SKYBLUE (-6600 4400);
FORCEPROP 1 LASTPIN (-6650 4550) $PN 1
J 0
(-6640 4530);
DISPLAY 0.617021 (-6640 4530);
PAINT GREEN (-6640 4530);
FORCEPROP 1 LAST LOCATION C2D27
J 0
(-6600 4600);
DISPLAY 0.617021 (-6600 4600);
PAINT AQUA (-6600 4600);
FORCEPROP 1 LAST VOLTAGE 4V
J 0
(-6600 4500);
DISPLAY 0.617021 (-6600 4500);
PAINT SKYBLUE (-6600 4500);
FORCEPROP 1 LAST VALUE 22.0UF
J 0
(-6600 4550);
DISPLAY 0.617021 (-6600 4550);
PAINT SKYBLUE (-6600 4550);
FORCEPROP 2 LAST CDS_LOCATION C2D27
J 0
(-6600 4550);
DISPLAY 0.617021 (-6600 4550);
PAINT AQUA (-6600 4550);
DISPLAY INVISIBLE (-6600 4550);
FORCEPROP 2 LAST BOM_COST PROC
J 0
(-6650 4450);
PAINT MONO (-6650 4450);
DISPLAY INVISIBLE (-6650 4450);
FORCEPROP 2 LAST CDS_LIB dev_discrete
J 0
(-6650 4450);
PAINT ORANGE (-6650 4450);
DISPLAY INVISIBLE (-6650 4450);
FORCEPROP 2 LAST CDS_SEC 1
J 0
(-6600 4650);
PAINT MONO (-6600 4650);
DISPLAY INVISIBLE (-6600 4650);
FORCEPROP 2 LAST $SEC 1
J 0
(-6600 4650);
PAINT MONO (-6600 4650);
DISPLAY INVISIBLE (-6600 4650);
FORCEPROP 1 LAST PATH I66
J 0
(-6600 4600);
DISPLAY 0.978723 (-6600 4600);
PAINT WHITE (-6600 4600);
DISPLAY INVISIBLE (-6600 4600);
FORCEPROP 2 LAST ROOM PVCCIN_CPU1_DECAP_VR
J 0
(-6600 4550);
PAINT ORANGE (-6600 4550);
DISPLAY INVISIBLE (-6600 4550);
FORCEADD GND..1
(-7750 4175);
FORCEPROP 3 LASTPIN (-7750 4225) SIG_NAME GND\g
J 0
(-7740 4235);
DISPLAY 0.659574 (-7740 4235);
PAINT MONO (-7740 4235);
DISPLAY INVISIBLE (-7740 4235);
FORCEPROP 1 LAST VOLTAGE 0
J 0
(-7750 4175);
PAINT SKYBLUE (-7750 4175);
DISPLAY INVISIBLE (-7750 4175);
FORCEPROP 2 LAST CDS_LIB mstr_symbols
J 0
(-7750 4175);
PAINT ORANGE (-7750 4175);
DISPLAY INVISIBLE (-7750 4175);
FORCEPROP 1 LAST SIZE 1B
J 0
(-7675 4125);
DISPLAY 0.893617 (-7675 4125);
PAINT GREEN (-7675 4125);
DISPLAY INVISIBLE (-7675 4125);
FORCEPROP 1 LAST BODY_TYPE PLUMBING
J 0
(-7795 4132);
DISPLAY 0.340426 (-7795 4132);
PAINT GREEN (-7795 4132);
DISPLAY INVISIBLE (-7795 4132);
FORCEPROP 1 LAST PATH I67
J 0
(-7675 4175);
DISPLAY 0.872340 (-7675 4175);
PAINT AQUA (-7675 4175);
DISPLAY INVISIBLE (-7675 4175);
FORCEPROP 2 LAST ROOM PVCCIN_CPU1_DECAP_VR
J 0
(-8300 4250);
PAINT ORANGE (-8300 4250);
DISPLAY INVISIBLE (-8300 4250);
FORCEPROP 1 LAST HDL_POWER GND
J 0
(-7750 4325);
DISPLAY 0.893617 (-7750 4325);
PAINT GREEN (-7750 4325);
DISPLAY INVISIBLE (-7750 4325);
FORCEADD CAP_A..1
(-7350 4450);
FORCEPROP 0 LAST GROUP PWR_MLCC_CAP
J 0
(-7294 4212);
DISPLAY 0.638298 (-7294 4212);
PAINT BROWN (-7294 4212);
DISPLAY BOTH (-7294 4212);
FORCEPROP 1 LAST LOCATION C3D2
J 0
(-7300 4600);
DISPLAY 0.617021 (-7300 4600);
PAINT AQUA (-7300 4600);
FORCEPROP 1 LAST TOLERANCE 20%
J 0
(-7300 4450);
DISPLAY 0.617021 (-7300 4450);
PAINT SKYBLUE (-7300 4450);
FORCEPROP 1 LASTPIN (-7350 4350) $PN 2
J 0
(-7340 4330);
DISPLAY 0.617021 (-7340 4330);
PAINT GREEN (-7340 4330);
FORCEPROP 1 LAST MATERIAL X6S
J 0
(-7300 4400);
DISPLAY 0.617021 (-7300 4400);
PAINT SKYBLUE (-7300 4400);
FORCEPROP 1 LAST PACK_TYPE 0603V
J 0
(-7300 4300);
DISPLAY 0.617021 (-7300 4300);
PAINT SKYBLUE (-7300 4300);
FORCEPROP 1 LAST PART_NUMBER E15431-004
J 0
(-7300 4350);
DISPLAY 0.617021 (-7300 4350);
PAINT BLUE (-7300 4350);
FORCEPROP 1 LASTPIN (-7350 4550) $PN 1
J 0
(-7340 4530);
DISPLAY 0.617021 (-7340 4530);
PAINT GREEN (-7340 4530);
FORCEPROP 1 LAST VOLTAGE 4V
J 0
(-7300 4500);
DISPLAY 0.617021 (-7300 4500);
PAINT SKYBLUE (-7300 4500);
FORCEPROP 1 LAST VALUE 22.0UF
J 0
(-7300 4550);
DISPLAY 0.617021 (-7300 4550);
PAINT SKYBLUE (-7300 4550);
FORCEPROP 2 LAST ROOM PVCCIN_CPU1_DECAP_VR
J 0
(-7300 4550);
PAINT ORANGE (-7300 4550);
DISPLAY INVISIBLE (-7300 4550);
FORCEPROP 1 LAST PATH I69
J 0
(-7300 4600);
DISPLAY 0.978723 (-7300 4600);
PAINT WHITE (-7300 4600);
DISPLAY INVISIBLE (-7300 4600);
FORCEPROP 2 LAST $SEC 1
J 0
(-7300 4650);
PAINT MONO (-7300 4650);
DISPLAY INVISIBLE (-7300 4650);
FORCEPROP 2 LAST CDS_SEC 1
J 0
(-7300 4650);
PAINT MONO (-7300 4650);
DISPLAY INVISIBLE (-7300 4650);
FORCEPROP 2 LAST CDS_LIB dev_discrete
J 0
(-7350 4450);
PAINT ORANGE (-7350 4450);
DISPLAY INVISIBLE (-7350 4450);
FORCEPROP 2 LAST BOM_COST PROC
J 0
(-7350 4450);
PAINT MONO (-7350 4450);
DISPLAY INVISIBLE (-7350 4450);
FORCEPROP 2 LAST CDS_LOCATION C3D2
J 0
(-7300 4550);
DISPLAY 0.617021 (-7300 4550);
PAINT AQUA (-7300 4550);
DISPLAY INVISIBLE (-7300 4550);
FORCEADD CAP_A..1
(-2450 4450);
FORCEPROP 1 LAST MATERIAL X6S
J 0
(-2400 4350);
DISPLAY 0.617021 (-2400 4350);
PAINT SKYBLUE (-2400 4350);
FORCEPROP 1 LAST VALUE 22.0UF
J 0
(-2400 4500);
DISPLAY 0.617021 (-2400 4500);
PAINT SKYBLUE (-2400 4500);
FORCEPROP 0 LAST GROUP PWR_MCP_CAP
J 0
(-2400 4200);
DISPLAY 0.638298 (-2400 4200);
PAINT BROWN (-2400 4200);
DISPLAY BOTH (-2400 4200);
FORCEPROP 1 LAST VOLTAGE 4V
J 0
(-2400 4450);
DISPLAY 0.617021 (-2400 4450);
PAINT SKYBLUE (-2400 4450);
FORCEPROP 1 LAST TOLERANCE 20%
J 0
(-2400 4400);
DISPLAY 0.617021 (-2400 4400);
PAINT SKYBLUE (-2400 4400);
FORCEPROP 1 LAST PART_NUMBER E15431-004
J 0
(-2400 4300);
DISPLAY 0.617021 (-2400 4300);
PAINT BLUE (-2400 4300);
FORCEPROP 1 LASTPIN (-2450 4350) $PN 2
J 0
(-2440 4330);
DISPLAY 0.617021 (-2440 4330);
PAINT GREEN (-2440 4330);
FORCEPROP 1 LAST PACK_TYPE 0603V
J 0
(-2400 4250);
DISPLAY 0.617021 (-2400 4250);
PAINT SKYBLUE (-2400 4250);
FORCEPROP 1 LASTPIN (-2450 4550) $PN 1
J 0
(-2440 4530);
DISPLAY 0.617021 (-2440 4530);
PAINT GREEN (-2440 4530);
FORCEPROP 1 LAST LOCATION C3D11
J 0
(-2400 4550);
DISPLAY 0.617021 (-2400 4550);
PAINT AQUA (-2400 4550);
FORCEPROP 2 LAST ROOM PVCCIN_CPU1_DECAP_VR
J 0
(-2400 4550);
PAINT ORANGE (-2400 4550);
DISPLAY INVISIBLE (-2400 4550);
FORCEPROP 1 LAST PATH I7
J 0
(-2400 4600);
DISPLAY 0.978723 (-2400 4600);
PAINT WHITE (-2400 4600);
DISPLAY INVISIBLE (-2400 4600);
FORCEPROP 2 LAST $SEC 1
J 0
(-2400 4650);
PAINT MONO (-2400 4650);
DISPLAY INVISIBLE (-2400 4650);
FORCEPROP 2 LAST CDS_SEC 1
J 0
(-2400 4650);
PAINT MONO (-2400 4650);
DISPLAY INVISIBLE (-2400 4650);
FORCEPROP 2 LAST CDS_LIB dev_discrete
J 0
(-2450 4450);
PAINT ORANGE (-2450 4450);
DISPLAY INVISIBLE (-2450 4450);
FORCEPROP 2 LAST BOM_COST PROC
J 0
(-2450 4450);
PAINT MONO (-2450 4450);
DISPLAY INVISIBLE (-2450 4450);
FORCEPROP 2 LAST CDS_LOCATION C3D11
J 0
(-2400 4550);
DISPLAY 0.617021 (-2400 4550);
PAINT AQUA (-2400 4550);
DISPLAY INVISIBLE (-2400 4550);
FORCEADD CAP_A..1
(-7650 4450);
FORCEPROP 1 LAST PACK_TYPE 0603V
J 0
(-7600 4300);
DISPLAY 0.617021 (-7600 4300);
PAINT SKYBLUE (-7600 4300);
FORCEPROP 0 LAST GROUP PWR_MLCC_CAP
J 0
(-7594 4262);
DISPLAY 0.638298 (-7594 4262);
PAINT BROWN (-7594 4262);
DISPLAY BOTH (-7594 4262);
FORCEPROP 1 LAST MATERIAL X6S
J 0
(-7600 4400);
DISPLAY 0.617021 (-7600 4400);
PAINT SKYBLUE (-7600 4400);
FORCEPROP 1 LAST PART_NUMBER E15431-004
J 0
(-7600 4350);
DISPLAY 0.617021 (-7600 4350);
PAINT BLUE (-7600 4350);
FORCEPROP 1 LASTPIN (-7650 4350) $PN 2
J 0
(-7640 4330);
DISPLAY 0.617021 (-7640 4330);
PAINT GREEN (-7640 4330);
FORCEPROP 1 LASTPIN (-7650 4550) $PN 1
J 0
(-7640 4530);
DISPLAY 0.617021 (-7640 4530);
PAINT GREEN (-7640 4530);
FORCEPROP 1 LAST TOLERANCE 20%
J 0
(-7600 4450);
DISPLAY 0.617021 (-7600 4450);
PAINT SKYBLUE (-7600 4450);
FORCEPROP 1 LAST VOLTAGE 4V
J 0
(-7600 4500);
DISPLAY 0.617021 (-7600 4500);
PAINT SKYBLUE (-7600 4500);
FORCEPROP 1 LAST VALUE 22.0UF
J 0
(-7600 4550);
DISPLAY 0.617021 (-7600 4550);
PAINT SKYBLUE (-7600 4550);
FORCEPROP 1 LAST LOCATION C2D36
J 0
(-7600 4600);
DISPLAY 0.617021 (-7600 4600);
PAINT AQUA (-7600 4600);
FORCEPROP 2 LAST CDS_LOCATION C2D36
J 0
(-7600 4550);
DISPLAY 0.617021 (-7600 4550);
PAINT AQUA (-7600 4550);
DISPLAY INVISIBLE (-7600 4550);
FORCEPROP 2 LAST CDS_LIB dev_discrete
J 0
(-7650 4450);
PAINT ORANGE (-7650 4450);
DISPLAY INVISIBLE (-7650 4450);
FORCEPROP 2 LAST CDS_SEC 1
J 0
(-7600 4650);
PAINT MONO (-7600 4650);
DISPLAY INVISIBLE (-7600 4650);
FORCEPROP 2 LAST $SEC 1
J 0
(-7600 4650);
PAINT MONO (-7600 4650);
DISPLAY INVISIBLE (-7600 4650);
FORCEPROP 1 LAST PATH I70
J 0
(-7600 4600);
DISPLAY 0.978723 (-7600 4600);
PAINT WHITE (-7600 4600);
DISPLAY INVISIBLE (-7600 4600);
FORCEPROP 2 LAST BOM_COST PROC
J 0
(-7650 4450);
PAINT MONO (-7650 4450);
DISPLAY INVISIBLE (-7650 4450);
FORCEPROP 2 LAST ROOM PVCCIN_CPU1_DECAP_VR
J 0
(-7600 4550);
PAINT ORANGE (-7600 4550);
DISPLAY INVISIBLE (-7600 4550);
FORCEADD PVCCIN_CPU1..1
(-7750 4750);
FORCEPROP 3 LASTPIN (-7750 4700) SIG_NAME PVCCIN_CPU1\g
J 0
(-7740 4710);
DISPLAY 0.659574 (-7740 4710);
PAINT MONO (-7740 4710);
DISPLAY INVISIBLE (-7740 4710);
FORCEPROP 1 LAST HDL_POWER PVCCIN_CPU1
J 1
(-7750 4800);
DISPLAY 0.872340 (-7750 4800);
PAINT GREEN (-7750 4800);
DISPLAY INVISIBLE (-7750 4800);
FORCEPROP 2 LAST ROOM PVCCIN_CPU1_DECAP_VR
J 0
(-7500 4850);
PAINT ORANGE (-7500 4850);
DISPLAY INVISIBLE (-7500 4850);
FORCEPROP 1 LAST PATH I71
J 0
(-7700 4775);
DISPLAY 0.872340 (-7700 4775);
PAINT AQUA (-7700 4775);
DISPLAY INVISIBLE (-7700 4775);
FORCEPROP 1 LAST BODY_TYPE PLUMBING
J 0
(-7795 4707);
DISPLAY 0.340426 (-7795 4707);
PAINT GREEN (-7795 4707);
DISPLAY INVISIBLE (-7795 4707);
FORCEPROP 2 LAST CDS_LIB mstr_symbols
J 0
(-7750 4750);
PAINT ORANGE (-7750 4750);
DISPLAY INVISIBLE (-7750 4750);
FORCEPROP 1 LAST VOLTAGE 2.0V
J 0
(-7795 4707);
DISPLAY 0.340426 (-7795 4707);
PAINT SKYBLUE (-7795 4707);
DISPLAY INVISIBLE (-7795 4707);
FORCEADD CAP_A..1
(-4700 3750);
FORCEPROP 0 LAST GROUP PWR_MLCC_CAP
J 0
(-4644 3562);
DISPLAY 0.638298 (-4644 3562);
PAINT BROWN (-4644 3562);
DISPLAY BOTH (-4644 3562);
FORCEPROP 1 LAST MATERIAL X6S
J 0
(-4650 3700);
DISPLAY 0.617021 (-4650 3700);
PAINT SKYBLUE (-4650 3700);
FORCEPROP 1 LASTPIN (-4700 3650) $PN 2
J 0
(-4690 3630);
DISPLAY 0.617021 (-4690 3630);
PAINT GREEN (-4690 3630);
FORCEPROP 1 LAST PART_NUMBER E15431-004
J 0
(-4650 3650);
DISPLAY 0.617021 (-4650 3650);
PAINT BLUE (-4650 3650);
FORCEPROP 1 LAST TOLERANCE 20%
J 0
(-4650 3750);
DISPLAY 0.617021 (-4650 3750);
PAINT SKYBLUE (-4650 3750);
FORCEPROP 1 LAST VALUE 22.0UF
J 0
(-4650 3850);
DISPLAY 0.617021 (-4650 3850);
PAINT SKYBLUE (-4650 3850);
FORCEPROP 1 LAST LOCATION C2D13
J 0
(-4650 3900);
DISPLAY 0.617021 (-4650 3900);
PAINT AQUA (-4650 3900);
FORCEPROP 1 LASTPIN (-4700 3850) $PN 1
J 0
(-4690 3830);
DISPLAY 0.617021 (-4690 3830);
PAINT GREEN (-4690 3830);
FORCEPROP 1 LAST VOLTAGE 4V
J 0
(-4650 3800);
DISPLAY 0.617021 (-4650 3800);
PAINT SKYBLUE (-4650 3800);
FORCEPROP 1 LAST PACK_TYPE 0603V
J 0
(-4650 3600);
DISPLAY 0.617021 (-4650 3600);
PAINT SKYBLUE (-4650 3600);
FORCEPROP 2 LAST ROOM PVCCIN_CPU1_DECAP_VR
J 0
(-4650 3850);
PAINT ORANGE (-4650 3850);
DISPLAY INVISIBLE (-4650 3850);
FORCEPROP 1 LAST PATH I73
J 0
(-4650 3900);
DISPLAY 0.978723 (-4650 3900);
PAINT WHITE (-4650 3900);
DISPLAY INVISIBLE (-4650 3900);
FORCEPROP 2 LAST $SEC 1
J 0
(-4650 3950);
PAINT MONO (-4650 3950);
DISPLAY INVISIBLE (-4650 3950);
FORCEPROP 2 LAST CDS_SEC 1
J 0
(-4650 3950);
PAINT MONO (-4650 3950);
DISPLAY INVISIBLE (-4650 3950);
FORCEPROP 2 LAST CDS_LIB dev_discrete
J 0
(-4700 3750);
PAINT ORANGE (-4700 3750);
DISPLAY INVISIBLE (-4700 3750);
FORCEPROP 2 LAST BOM_COST PROC
J 0
(-4700 3750);
PAINT MONO (-4700 3750);
DISPLAY INVISIBLE (-4700 3750);
FORCEPROP 2 LAST CDS_LOCATION C2D13
J 0
(-4650 3850);
DISPLAY 0.617021 (-4650 3850);
PAINT AQUA (-4650 3850);
DISPLAY INVISIBLE (-4650 3850);
FORCEADD GND..1
(-5900 3475);
FORCEPROP 3 LASTPIN (-5900 3525) SIG_NAME GND\g
J 0
(-5890 3535);
DISPLAY 0.659574 (-5890 3535);
PAINT MONO (-5890 3535);
DISPLAY INVISIBLE (-5890 3535);
FORCEPROP 1 LAST VOLTAGE 0
J 0
(-5900 3475);
PAINT SKYBLUE (-5900 3475);
DISPLAY INVISIBLE (-5900 3475);
FORCEPROP 1 LAST SIZE 1B
J 0
(-5825 3425);
DISPLAY 0.893617 (-5825 3425);
PAINT GREEN (-5825 3425);
DISPLAY INVISIBLE (-5825 3425);
FORCEPROP 2 LAST CDS_LIB mstr_symbols
J 0
(-5900 3475);
PAINT ORANGE (-5900 3475);
DISPLAY INVISIBLE (-5900 3475);
FORCEPROP 1 LAST BODY_TYPE PLUMBING
J 0
(-5945 3432);
DISPLAY 0.340426 (-5945 3432);
PAINT GREEN (-5945 3432);
DISPLAY INVISIBLE (-5945 3432);
FORCEPROP 1 LAST PATH I74
J 0
(-5825 3475);
DISPLAY 0.872340 (-5825 3475);
PAINT AQUA (-5825 3475);
DISPLAY INVISIBLE (-5825 3475);
FORCEPROP 2 LAST ROOM PVCCIN_CPU1_DECAP_VR
J 0
(-6450 3550);
PAINT ORANGE (-6450 3550);
DISPLAY INVISIBLE (-6450 3550);
FORCEPROP 1 LAST HDL_POWER GND
J 0
(-5900 3625);
DISPLAY 0.893617 (-5900 3625);
PAINT GREEN (-5900 3625);
DISPLAY INVISIBLE (-5900 3625);
FORCEADD CAP_A..1
(-5000 3750);
FORCEPROP 1 LAST PACK_TYPE 0603V
J 0
(-4950 3600);
DISPLAY 0.617021 (-4950 3600);
PAINT SKYBLUE (-4950 3600);
FORCEPROP 0 LAST GROUP PWR_MLCC_CAP
J 0
(-4944 3512);
DISPLAY 0.638298 (-4944 3512);
PAINT BROWN (-4944 3512);
DISPLAY BOTH (-4944 3512);
FORCEPROP 1 LAST MATERIAL X6S
J 0
(-4950 3700);
DISPLAY 0.617021 (-4950 3700);
PAINT SKYBLUE (-4950 3700);
FORCEPROP 1 LAST TOLERANCE 20%
J 0
(-4950 3750);
DISPLAY 0.617021 (-4950 3750);
PAINT SKYBLUE (-4950 3750);
FORCEPROP 1 LAST LOCATION C2D19
J 0
(-4950 3900);
DISPLAY 0.617021 (-4950 3900);
PAINT AQUA (-4950 3900);
FORCEPROP 1 LAST VALUE 22.0UF
J 0
(-4950 3850);
DISPLAY 0.617021 (-4950 3850);
PAINT SKYBLUE (-4950 3850);
FORCEPROP 1 LASTPIN (-5000 3850) $PN 1
J 0
(-4990 3830);
DISPLAY 0.617021 (-4990 3830);
PAINT GREEN (-4990 3830);
FORCEPROP 1 LAST PART_NUMBER E15431-004
J 0
(-4950 3650);
DISPLAY 0.617021 (-4950 3650);
PAINT BLUE (-4950 3650);
FORCEPROP 1 LAST VOLTAGE 4V
J 0
(-4950 3800);
DISPLAY 0.617021 (-4950 3800);
PAINT SKYBLUE (-4950 3800);
FORCEPROP 1 LASTPIN (-5000 3650) $PN 2
J 0
(-4990 3630);
DISPLAY 0.617021 (-4990 3630);
PAINT GREEN (-4990 3630);
FORCEPROP 2 LAST CDS_LOCATION C2D19
J 0
(-4950 3850);
DISPLAY 0.617021 (-4950 3850);
PAINT AQUA (-4950 3850);
DISPLAY INVISIBLE (-4950 3850);
FORCEPROP 2 LAST BOM_COST PROC
J 0
(-5000 3750);
PAINT MONO (-5000 3750);
DISPLAY INVISIBLE (-5000 3750);
FORCEPROP 2 LAST CDS_LIB dev_discrete
J 0
(-5000 3750);
PAINT ORANGE (-5000 3750);
DISPLAY INVISIBLE (-5000 3750);
FORCEPROP 2 LAST CDS_SEC 1
J 0
(-4950 3950);
PAINT MONO (-4950 3950);
DISPLAY INVISIBLE (-4950 3950);
FORCEPROP 2 LAST $SEC 1
J 0
(-4950 3950);
PAINT MONO (-4950 3950);
DISPLAY INVISIBLE (-4950 3950);
FORCEPROP 1 LAST PATH I75
J 0
(-4950 3900);
DISPLAY 0.978723 (-4950 3900);
PAINT WHITE (-4950 3900);
DISPLAY INVISIBLE (-4950 3900);
FORCEPROP 2 LAST ROOM PVCCIN_CPU1_DECAP_VR
J 0
(-4950 3850);
PAINT ORANGE (-4950 3850);
DISPLAY INVISIBLE (-4950 3850);
FORCEADD CAP_A..1
(-4800 3050);
FORCEPROP 1 LAST PACK_TYPE 0603V
J 0
(-4750 2900);
DISPLAY 0.617021 (-4750 2900);
PAINT SKYBLUE (-4750 2900);
FORCEPROP 0 LAST GROUP PWR_MLCC_CAP
J 0
(-4744 2862);
DISPLAY 0.638298 (-4744 2862);
PAINT BROWN (-4744 2862);
DISPLAY BOTH (-4744 2862);
FORCEPROP 1 LAST VALUE 22.0UF
J 0
(-4750 3150);
DISPLAY 0.617021 (-4750 3150);
PAINT SKYBLUE (-4750 3150);
FORCEPROP 1 LAST LOCATION C2D14
J 0
(-4750 3200);
DISPLAY 0.617021 (-4750 3200);
PAINT AQUA (-4750 3200);
FORCEPROP 1 LAST PART_NUMBER E15431-004
J 0
(-4750 2950);
DISPLAY 0.617021 (-4750 2950);
PAINT BLUE (-4750 2950);
FORCEPROP 1 LAST MATERIAL X6S
J 0
(-4750 3000);
DISPLAY 0.617021 (-4750 3000);
PAINT SKYBLUE (-4750 3000);
FORCEPROP 1 LASTPIN (-4800 2950) $PN 2
J 0
(-4790 2930);
DISPLAY 0.617021 (-4790 2930);
PAINT GREEN (-4790 2930);
FORCEPROP 1 LAST TOLERANCE 20%
J 0
(-4750 3050);
DISPLAY 0.617021 (-4750 3050);
PAINT SKYBLUE (-4750 3050);
FORCEPROP 1 LASTPIN (-4800 3150) $PN 1
J 0
(-4790 3130);
DISPLAY 0.617021 (-4790 3130);
PAINT GREEN (-4790 3130);
FORCEPROP 1 LAST VOLTAGE 4V
J 0
(-4750 3100);
DISPLAY 0.617021 (-4750 3100);
PAINT SKYBLUE (-4750 3100);
FORCEPROP 2 LAST CDS_LOCATION C2D14
J 0
(-4750 3150);
DISPLAY 0.617021 (-4750 3150);
PAINT AQUA (-4750 3150);
DISPLAY INVISIBLE (-4750 3150);
FORCEPROP 2 LAST BOM_COST PROC
J 0
(-4800 3050);
PAINT MONO (-4800 3050);
DISPLAY INVISIBLE (-4800 3050);
FORCEPROP 2 LAST CDS_LIB dev_discrete
J 0
(-4800 3050);
PAINT ORANGE (-4800 3050);
DISPLAY INVISIBLE (-4800 3050);
FORCEPROP 2 LAST CDS_SEC 1
J 0
(-4750 3250);
PAINT MONO (-4750 3250);
DISPLAY INVISIBLE (-4750 3250);
FORCEPROP 2 LAST $SEC 1
J 0
(-4750 3250);
PAINT MONO (-4750 3250);
DISPLAY INVISIBLE (-4750 3250);
FORCEPROP 1 LAST PATH I76
J 0
(-4750 3200);
DISPLAY 0.978723 (-4750 3200);
PAINT WHITE (-4750 3200);
DISPLAY INVISIBLE (-4750 3200);
FORCEPROP 2 LAST ROOM PVCCIN_CPU1_DECAP_VR
J 0
(-4750 3150);
PAINT ORANGE (-4750 3150);
DISPLAY INVISIBLE (-4750 3150);
FORCEADD GND..1
(-5900 2775);
FORCEPROP 3 LASTPIN (-5900 2825) SIG_NAME GND\g
J 0
(-5890 2835);
DISPLAY 0.659574 (-5890 2835);
PAINT MONO (-5890 2835);
DISPLAY INVISIBLE (-5890 2835);
FORCEPROP 1 LAST HDL_POWER GND
J 0
(-5900 2925);
DISPLAY 0.893617 (-5900 2925);
PAINT GREEN (-5900 2925);
DISPLAY INVISIBLE (-5900 2925);
FORCEPROP 2 LAST ROOM PVCCIN_CPU1_DECAP_VR
J 0
(-6450 2850);
PAINT ORANGE (-6450 2850);
DISPLAY INVISIBLE (-6450 2850);
FORCEPROP 1 LAST PATH I77
J 0
(-5825 2775);
DISPLAY 0.872340 (-5825 2775);
PAINT AQUA (-5825 2775);
DISPLAY INVISIBLE (-5825 2775);
FORCEPROP 1 LAST BODY_TYPE PLUMBING
J 0
(-5945 2732);
DISPLAY 0.340426 (-5945 2732);
PAINT GREEN (-5945 2732);
DISPLAY INVISIBLE (-5945 2732);
FORCEPROP 2 LAST CDS_LIB mstr_symbols
J 0
(-5900 2775);
PAINT ORANGE (-5900 2775);
DISPLAY INVISIBLE (-5900 2775);
FORCEPROP 1 LAST SIZE 1B
J 0
(-5825 2725);
DISPLAY 0.893617 (-5825 2725);
PAINT GREEN (-5825 2725);
DISPLAY INVISIBLE (-5825 2725);
FORCEPROP 1 LAST VOLTAGE 0
J 0
(-5900 2775);
PAINT SKYBLUE (-5900 2775);
DISPLAY INVISIBLE (-5900 2775);
FORCEADD CAP_A..1
(-5100 3050);
FORCEPROP 0 LAST GROUP PWR_MLCC_CAP
J 0
(-5044 2812);
DISPLAY 0.638298 (-5044 2812);
PAINT BROWN (-5044 2812);
DISPLAY BOTH (-5044 2812);
FORCEPROP 1 LAST MATERIAL X6S
J 0
(-5050 3000);
DISPLAY 0.617021 (-5050 3000);
PAINT SKYBLUE (-5050 3000);
FORCEPROP 1 LAST TOLERANCE 20%
J 0
(-5050 3050);
DISPLAY 0.617021 (-5050 3050);
PAINT SKYBLUE (-5050 3050);
FORCEPROP 1 LASTPIN (-5100 2950) $PN 2
J 0
(-5090 2930);
DISPLAY 0.617021 (-5090 2930);
PAINT GREEN (-5090 2930);
FORCEPROP 1 LASTPIN (-5100 3150) $PN 1
J 0
(-5090 3130);
DISPLAY 0.617021 (-5090 3130);
PAINT GREEN (-5090 3130);
FORCEPROP 1 LAST VALUE 22.0UF
J 0
(-5050 3150);
DISPLAY 0.617021 (-5050 3150);
PAINT SKYBLUE (-5050 3150);
FORCEPROP 1 LAST VOLTAGE 4V
J 0
(-5050 3100);
DISPLAY 0.617021 (-5050 3100);
PAINT SKYBLUE (-5050 3100);
FORCEPROP 1 LAST PACK_TYPE 0603V
J 0
(-5050 2900);
DISPLAY 0.617021 (-5050 2900);
PAINT SKYBLUE (-5050 2900);
FORCEPROP 1 LAST LOCATION C2D20
J 0
(-5050 3200);
DISPLAY 0.617021 (-5050 3200);
PAINT AQUA (-5050 3200);
FORCEPROP 1 LAST PART_NUMBER E15431-004
J 0
(-5050 2950);
DISPLAY 0.617021 (-5050 2950);
PAINT BLUE (-5050 2950);
FORCEPROP 2 LAST CDS_LOCATION C2D20
J 0
(-5050 3150);
DISPLAY 0.617021 (-5050 3150);
PAINT AQUA (-5050 3150);
DISPLAY INVISIBLE (-5050 3150);
FORCEPROP 2 LAST BOM_COST PROC
J 0
(-5100 3050);
PAINT MONO (-5100 3050);
DISPLAY INVISIBLE (-5100 3050);
FORCEPROP 2 LAST CDS_LIB dev_discrete
J 0
(-5100 3050);
PAINT ORANGE (-5100 3050);
DISPLAY INVISIBLE (-5100 3050);
FORCEPROP 2 LAST CDS_SEC 1
J 0
(-5050 3250);
PAINT MONO (-5050 3250);
DISPLAY INVISIBLE (-5050 3250);
FORCEPROP 2 LAST $SEC 1
J 0
(-5050 3250);
PAINT MONO (-5050 3250);
DISPLAY INVISIBLE (-5050 3250);
FORCEPROP 1 LAST PATH I79
J 0
(-5050 3200);
DISPLAY 0.978723 (-5050 3200);
PAINT WHITE (-5050 3200);
DISPLAY INVISIBLE (-5050 3200);
FORCEPROP 2 LAST ROOM PVCCIN_CPU1_DECAP_VR
J 0
(-5050 3150);
PAINT ORANGE (-5050 3150);
DISPLAY INVISIBLE (-5050 3150);
FORCEADD CAP_A..1
(-2975 4450);
FORCEPROP 1 LAST TOLERANCE 20%
J 0
(-2925 4400);
DISPLAY 0.617021 (-2925 4400);
PAINT SKYBLUE (-2925 4400);
FORCEPROP 1 LAST VOLTAGE 4V
J 0
(-2925 4450);
DISPLAY 0.617021 (-2925 4450);
PAINT SKYBLUE (-2925 4450);
FORCEPROP 0 LAST GROUP PWR_MCP_CAP
J 0
(-2925 4200);
DISPLAY 0.638298 (-2925 4200);
PAINT BROWN (-2925 4200);
DISPLAY BOTH (-2925 4200);
FORCEPROP 1 LASTPIN (-2975 4350) $PN 2
J 0
(-2965 4330);
DISPLAY 0.617021 (-2965 4330);
PAINT GREEN (-2965 4330);
FORCEPROP 1 LASTPIN (-2975 4550) $PN 1
J 0
(-2965 4530);
DISPLAY 0.617021 (-2965 4530);
PAINT GREEN (-2965 4530);
FORCEPROP 1 LAST MATERIAL X6S
J 0
(-2925 4350);
DISPLAY 0.617021 (-2925 4350);
PAINT SKYBLUE (-2925 4350);
FORCEPROP 1 LAST PACK_TYPE 0603V
J 0
(-2925 4250);
DISPLAY 0.617021 (-2925 4250);
PAINT SKYBLUE (-2925 4250);
FORCEPROP 1 LAST VALUE 22.0UF
J 0
(-2925 4500);
DISPLAY 0.617021 (-2925 4500);
PAINT SKYBLUE (-2925 4500);
FORCEPROP 1 LAST LOCATION C3D13
J 0
(-2925 4550);
DISPLAY 0.617021 (-2925 4550);
PAINT AQUA (-2925 4550);
FORCEPROP 1 LAST PART_NUMBER E15431-004
J 0
(-2925 4300);
DISPLAY 0.617021 (-2925 4300);
PAINT BLUE (-2925 4300);
FORCEPROP 2 LAST ROOM PVCCIN_CPU1_DECAP_VR
J 0
(-2925 4550);
PAINT ORANGE (-2925 4550);
DISPLAY INVISIBLE (-2925 4550);
FORCEPROP 1 LAST PATH I8
J 0
(-2925 4600);
DISPLAY 0.978723 (-2925 4600);
PAINT WHITE (-2925 4600);
DISPLAY INVISIBLE (-2925 4600);
FORCEPROP 2 LAST $SEC 1
J 0
(-2925 4650);
PAINT MONO (-2925 4650);
DISPLAY INVISIBLE (-2925 4650);
FORCEPROP 2 LAST CDS_SEC 1
J 0
(-2925 4650);
PAINT MONO (-2925 4650);
DISPLAY INVISIBLE (-2925 4650);
FORCEPROP 2 LAST CDS_LIB dev_discrete
J 0
(-2975 4450);
PAINT ORANGE (-2975 4450);
DISPLAY INVISIBLE (-2975 4450);
FORCEPROP 2 LAST BOM_COST PROC
J 0
(-2975 4450);
PAINT MONO (-2975 4450);
DISPLAY INVISIBLE (-2975 4450);
FORCEPROP 2 LAST CDS_LOCATION C3D13
J 0
(-2925 4550);
DISPLAY 0.617021 (-2925 4550);
PAINT AQUA (-2925 4550);
DISPLAY INVISIBLE (-2925 4550);
FORCEADD CAP_A..1
(-5400 3050);
FORCEPROP 1 LAST LOCATION C2D24
J 0
(-5350 3200);
DISPLAY 0.617021 (-5350 3200);
PAINT AQUA (-5350 3200);
FORCEPROP 1 LAST PART_NUMBER E15431-004
J 0
(-5350 2950);
DISPLAY 0.617021 (-5350 2950);
PAINT BLUE (-5350 2950);
FORCEPROP 1 LASTPIN (-5400 3150) $PN 1
J 0
(-5390 3130);
DISPLAY 0.617021 (-5390 3130);
PAINT GREEN (-5390 3130);
FORCEPROP 1 LAST VALUE 22.0UF
J 0
(-5350 3150);
DISPLAY 0.617021 (-5350 3150);
PAINT SKYBLUE (-5350 3150);
FORCEPROP 1 LAST VOLTAGE 4V
J 0
(-5350 3100);
DISPLAY 0.617021 (-5350 3100);
PAINT SKYBLUE (-5350 3100);
FORCEPROP 1 LASTPIN (-5400 2950) $PN 2
J 0
(-5390 2930);
DISPLAY 0.617021 (-5390 2930);
PAINT GREEN (-5390 2930);
FORCEPROP 1 LAST TOLERANCE 20%
J 0
(-5350 3050);
DISPLAY 0.617021 (-5350 3050);
PAINT SKYBLUE (-5350 3050);
FORCEPROP 1 LAST MATERIAL X6S
J 0
(-5350 3000);
DISPLAY 0.617021 (-5350 3000);
PAINT SKYBLUE (-5350 3000);
FORCEPROP 1 LAST PACK_TYPE 0603V
J 0
(-5350 2900);
DISPLAY 0.617021 (-5350 2900);
PAINT SKYBLUE (-5350 2900);
FORCEPROP 0 LAST GROUP PWR_MLCC_CAP
J 0
(-5344 2862);
DISPLAY 0.638298 (-5344 2862);
PAINT BROWN (-5344 2862);
DISPLAY BOTH (-5344 2862);
FORCEPROP 2 LAST CDS_LOCATION C2D24
J 0
(-5350 3150);
DISPLAY 0.617021 (-5350 3150);
PAINT AQUA (-5350 3150);
DISPLAY INVISIBLE (-5350 3150);
FORCEPROP 2 LAST BOM_COST PROC
J 0
(-5400 3050);
PAINT MONO (-5400 3050);
DISPLAY INVISIBLE (-5400 3050);
FORCEPROP 2 LAST CDS_LIB dev_discrete
J 0
(-5400 3050);
PAINT ORANGE (-5400 3050);
DISPLAY INVISIBLE (-5400 3050);
FORCEPROP 2 LAST CDS_SEC 1
J 0
(-5350 3250);
PAINT MONO (-5350 3250);
DISPLAY INVISIBLE (-5350 3250);
FORCEPROP 2 LAST $SEC 1
J 0
(-5350 3250);
PAINT MONO (-5350 3250);
DISPLAY INVISIBLE (-5350 3250);
FORCEPROP 1 LAST PATH I80
J 0
(-5350 3200);
DISPLAY 0.978723 (-5350 3200);
PAINT WHITE (-5350 3200);
DISPLAY INVISIBLE (-5350 3200);
FORCEPROP 2 LAST ROOM PVCCIN_CPU1_DECAP_VR
J 0
(-5350 3150);
PAINT ORANGE (-5350 3150);
DISPLAY INVISIBLE (-5350 3150);
FORCEADD CAP_A..1
(-5300 3750);
FORCEPROP 0 LAST GROUP PWR_MLCC_CAP
J 0
(-5244 3562);
DISPLAY 0.638298 (-5244 3562);
PAINT BROWN (-5244 3562);
DISPLAY BOTH (-5244 3562);
FORCEPROP 1 LAST VOLTAGE 4V
J 0
(-5250 3800);
DISPLAY 0.617021 (-5250 3800);
PAINT SKYBLUE (-5250 3800);
FORCEPROP 1 LAST VALUE 22.0UF
J 0
(-5250 3850);
DISPLAY 0.617021 (-5250 3850);
PAINT SKYBLUE (-5250 3850);
FORCEPROP 1 LASTPIN (-5300 3850) $PN 1
J 0
(-5290 3830);
DISPLAY 0.617021 (-5290 3830);
PAINT GREEN (-5290 3830);
FORCEPROP 1 LAST LOCATION C2D25
J 0
(-5250 3900);
DISPLAY 0.617021 (-5250 3900);
PAINT AQUA (-5250 3900);
FORCEPROP 1 LAST PACK_TYPE 0603V
J 0
(-5250 3600);
DISPLAY 0.617021 (-5250 3600);
PAINT SKYBLUE (-5250 3600);
FORCEPROP 1 LASTPIN (-5300 3650) $PN 2
J 0
(-5290 3630);
DISPLAY 0.617021 (-5290 3630);
PAINT GREEN (-5290 3630);
FORCEPROP 1 LAST TOLERANCE 20%
J 0
(-5250 3750);
DISPLAY 0.617021 (-5250 3750);
PAINT SKYBLUE (-5250 3750);
FORCEPROP 1 LAST PART_NUMBER E15431-004
J 0
(-5250 3650);
DISPLAY 0.617021 (-5250 3650);
PAINT BLUE (-5250 3650);
FORCEPROP 1 LAST MATERIAL X6S
J 0
(-5250 3700);
DISPLAY 0.617021 (-5250 3700);
PAINT SKYBLUE (-5250 3700);
FORCEPROP 2 LAST ROOM PVCCIN_CPU1_DECAP_VR
J 0
(-5250 3850);
PAINT ORANGE (-5250 3850);
DISPLAY INVISIBLE (-5250 3850);
FORCEPROP 1 LAST PATH I82
J 0
(-5250 3900);
DISPLAY 0.978723 (-5250 3900);
PAINT WHITE (-5250 3900);
DISPLAY INVISIBLE (-5250 3900);
FORCEPROP 2 LAST $SEC 1
J 0
(-5250 3950);
PAINT MONO (-5250 3950);
DISPLAY INVISIBLE (-5250 3950);
FORCEPROP 2 LAST CDS_SEC 1
J 0
(-5250 3950);
PAINT MONO (-5250 3950);
DISPLAY INVISIBLE (-5250 3950);
FORCEPROP 2 LAST CDS_LIB dev_discrete
J 0
(-5300 3750);
PAINT ORANGE (-5300 3750);
DISPLAY INVISIBLE (-5300 3750);
FORCEPROP 2 LAST BOM_COST PROC
J 0
(-5300 3750);
PAINT MONO (-5300 3750);
DISPLAY INVISIBLE (-5300 3750);
FORCEPROP 2 LAST CDS_LOCATION C2D25
J 0
(-5250 3850);
DISPLAY 0.617021 (-5250 3850);
PAINT AQUA (-5250 3850);
DISPLAY INVISIBLE (-5250 3850);
FORCEADD CAP_A..1
(-5600 3750);
FORCEPROP 1 LAST VOLTAGE 4V
J 0
(-5550 3800);
DISPLAY 0.617021 (-5550 3800);
PAINT SKYBLUE (-5550 3800);
FORCEPROP 1 LAST MATERIAL X6S
J 0
(-5550 3700);
DISPLAY 0.617021 (-5550 3700);
PAINT SKYBLUE (-5550 3700);
FORCEPROP 1 LAST PART_NUMBER E15431-004
J 0
(-5550 3650);
DISPLAY 0.617021 (-5550 3650);
PAINT BLUE (-5550 3650);
FORCEPROP 1 LAST VALUE 22.0UF
J 0
(-5550 3850);
DISPLAY 0.617021 (-5550 3850);
PAINT SKYBLUE (-5550 3850);
FORCEPROP 1 LAST LOCATION C2D30
J 0
(-5550 3900);
DISPLAY 0.617021 (-5550 3900);
PAINT AQUA (-5550 3900);
FORCEPROP 1 LASTPIN (-5600 3850) $PN 1
J 0
(-5590 3830);
DISPLAY 0.617021 (-5590 3830);
PAINT GREEN (-5590 3830);
FORCEPROP 1 LASTPIN (-5600 3650) $PN 2
J 0
(-5590 3630);
DISPLAY 0.617021 (-5590 3630);
PAINT GREEN (-5590 3630);
FORCEPROP 1 LAST PACK_TYPE 0603V
J 0
(-5550 3600);
DISPLAY 0.617021 (-5550 3600);
PAINT SKYBLUE (-5550 3600);
FORCEPROP 1 LAST TOLERANCE 20%
J 0
(-5550 3750);
DISPLAY 0.617021 (-5550 3750);
PAINT SKYBLUE (-5550 3750);
FORCEPROP 0 LAST GROUP PWR_MLCC_CAP
J 0
(-5544 3512);
DISPLAY 0.638298 (-5544 3512);
PAINT BROWN (-5544 3512);
DISPLAY BOTH (-5544 3512);
FORCEPROP 2 LAST ROOM PVCCIN_CPU1_DECAP_VR
J 0
(-5550 3850);
PAINT ORANGE (-5550 3850);
DISPLAY INVISIBLE (-5550 3850);
FORCEPROP 1 LAST PATH I83
J 0
(-5550 3900);
DISPLAY 0.978723 (-5550 3900);
PAINT WHITE (-5550 3900);
DISPLAY INVISIBLE (-5550 3900);
FORCEPROP 2 LAST $SEC 1
J 0
(-5550 3950);
PAINT MONO (-5550 3950);
DISPLAY INVISIBLE (-5550 3950);
FORCEPROP 2 LAST CDS_SEC 1
J 0
(-5550 3950);
PAINT MONO (-5550 3950);
DISPLAY INVISIBLE (-5550 3950);
FORCEPROP 2 LAST CDS_LIB dev_discrete
J 0
(-5600 3750);
PAINT ORANGE (-5600 3750);
DISPLAY INVISIBLE (-5600 3750);
FORCEPROP 2 LAST BOM_COST PROC
J 0
(-5600 3750);
PAINT MONO (-5600 3750);
DISPLAY INVISIBLE (-5600 3750);
FORCEPROP 2 LAST CDS_LOCATION C2D30
J 0
(-5550 3850);
DISPLAY 0.617021 (-5550 3850);
PAINT AQUA (-5550 3850);
DISPLAY INVISIBLE (-5550 3850);
FORCEADD CAP_A..1
(-5900 3750);
FORCEPROP 0 LAST GROUP PWR_MLCC_CAP
J 0
(-5844 3562);
DISPLAY 0.638298 (-5844 3562);
PAINT BROWN (-5844 3562);
DISPLAY BOTH (-5844 3562);
FORCEPROP 1 LAST VOLTAGE 4V
J 0
(-5850 3800);
DISPLAY 0.617021 (-5850 3800);
PAINT SKYBLUE (-5850 3800);
FORCEPROP 1 LAST TOLERANCE 20%
J 0
(-5850 3750);
DISPLAY 0.617021 (-5850 3750);
PAINT SKYBLUE (-5850 3750);
FORCEPROP 1 LAST PACK_TYPE 0603V
J 0
(-5850 3600);
DISPLAY 0.617021 (-5850 3600);
PAINT SKYBLUE (-5850 3600);
FORCEPROP 1 LAST PART_NUMBER E15431-004
J 0
(-5850 3650);
DISPLAY 0.617021 (-5850 3650);
PAINT BLUE (-5850 3650);
FORCEPROP 1 LAST MATERIAL X6S
J 0
(-5850 3700);
DISPLAY 0.617021 (-5850 3700);
PAINT SKYBLUE (-5850 3700);
FORCEPROP 1 LASTPIN (-5900 3650) $PN 2
J 0
(-5890 3630);
DISPLAY 0.617021 (-5890 3630);
PAINT GREEN (-5890 3630);
FORCEPROP 1 LASTPIN (-5900 3850) $PN 1
J 0
(-5890 3830);
DISPLAY 0.617021 (-5890 3830);
PAINT GREEN (-5890 3830);
FORCEPROP 1 LAST LOCATION C2D33
J 0
(-5850 3900);
DISPLAY 0.617021 (-5850 3900);
PAINT AQUA (-5850 3900);
FORCEPROP 1 LAST VALUE 22.0UF
J 0
(-5850 3850);
DISPLAY 0.617021 (-5850 3850);
PAINT SKYBLUE (-5850 3850);
FORCEPROP 2 LAST ROOM PVCCIN_CPU1_DECAP_VR
J 0
(-5850 3850);
PAINT ORANGE (-5850 3850);
DISPLAY INVISIBLE (-5850 3850);
FORCEPROP 1 LAST PATH I85
J 0
(-5850 3900);
DISPLAY 0.978723 (-5850 3900);
PAINT WHITE (-5850 3900);
DISPLAY INVISIBLE (-5850 3900);
FORCEPROP 2 LAST $SEC 1
J 0
(-5850 3950);
PAINT MONO (-5850 3950);
DISPLAY INVISIBLE (-5850 3950);
FORCEPROP 2 LAST CDS_SEC 1
J 0
(-5850 3950);
PAINT MONO (-5850 3950);
DISPLAY INVISIBLE (-5850 3950);
FORCEPROP 2 LAST CDS_LIB dev_discrete
J 0
(-5900 3750);
PAINT ORANGE (-5900 3750);
DISPLAY INVISIBLE (-5900 3750);
FORCEPROP 2 LAST BOM_COST PROC
J 0
(-5900 3750);
PAINT MONO (-5900 3750);
DISPLAY INVISIBLE (-5900 3750);
FORCEPROP 2 LAST CDS_LOCATION C2D33
J 0
(-5850 3850);
DISPLAY 0.617021 (-5850 3850);
PAINT AQUA (-5850 3850);
DISPLAY INVISIBLE (-5850 3850);
FORCEADD CAP..1
(-5650 2200);
FORCEPROP 0 LAST GROUP PWR_MLCC_CAP
J 0
(-5594 1987);
DISPLAY 0.638298 (-5594 1987);
PAINT BROWN (-5594 1987);
DISPLAY BOTH (-5594 1987);
FORCEPROP 1 LASTPIN (-5650 2300) $PN 1
J 0
(-5640 2280);
DISPLAY 0.617021 (-5640 2280);
PAINT GREEN (-5640 2280);
FORCEPROP 1 LASTPIN (-5650 2100) $PN 2
J 0
(-5640 2080);
DISPLAY 0.617021 (-5640 2080);
PAINT GREEN (-5640 2080);
FORCEPROP 1 LAST TOLERANCE 20%
J 0
(-5600 2200);
DISPLAY 0.617021 (-5600 2200);
PAINT SKYBLUE (-5600 2200);
FORCEPROP 1 LAST PART_NUMBER C95333-006
R 1
J 0
(-5700 2100);
DISPLAY 0.617021 (-5700 2100);
PAINT BLUE (-5700 2100);
FORCEPROP 1 LAST MATERIAL X6S
J 0
(-5600 2150);
DISPLAY 0.638298 (-5600 2150);
PAINT SKYBLUE (-5600 2150);
FORCEPROP 1 LAST PACK_TYPE 0805
J 0
(-5600 2100);
DISPLAY 0.617021 (-5600 2100);
PAINT SKYBLUE (-5600 2100);
FORCEPROP 1 LAST VOLTAGE 4V
J 0
(-5600 2250);
DISPLAY 0.638298 (-5600 2250);
PAINT SKYBLUE (-5600 2250);
FORCEPROP 1 LAST VALUE 47UF
J 0
(-5600 2300);
DISPLAY 0.617021 (-5600 2300);
PAINT SKYBLUE (-5600 2300);
FORCEPROP 1 LAST LOCATION C8P20
J 0
(-5600 2350);
DISPLAY 0.617021 (-5600 2350);
PAINT AQUA (-5600 2350);
FORCEPROP 2 LAST CDS_LIB mstr_discrete
J 0
(-5650 2200);
PAINT ORANGE (-5650 2200);
DISPLAY INVISIBLE (-5650 2200);
FORCEPROP 2 LAST BOM_COST PROC
J 0
(-5650 2200);
PAINT MONO (-5650 2200);
DISPLAY INVISIBLE (-5650 2200);
FORCEPROP 2 LAST CDS_SEC 1
J 0
(-5600 2400);
DISPLAY 1.021277 (-5600 2400);
PAINT ORANGE (-5600 2400);
DISPLAY INVISIBLE (-5600 2400);
FORCEPROP 2 LAST $SEC 1
J 0
(-5600 2400);
DISPLAY 0.680851 (-5600 2400);
PAINT MONO (-5600 2400);
DISPLAY INVISIBLE (-5600 2400);
FORCEPROP 2 LAST CDS_LOCATION C8P20
J 0
(-5600 2300);
DISPLAY 0.617021 (-5600 2300);
PAINT AQUA (-5600 2300);
DISPLAY INVISIBLE (-5600 2300);
FORCEPROP 1 LAST PATH I89
J 0
(-5600 2350);
DISPLAY 0.978723 (-5600 2350);
PAINT WHITE (-5600 2350);
DISPLAY INVISIBLE (-5600 2350);
FORCEPROP 2 LAST ROOM PVCCIN_CPU1_DECAP_VR
J 0
(-5575 2300);
PAINT ORANGE (-5575 2300);
DISPLAY INVISIBLE (-5575 2300);
FORCEADD CAP_A..1
(-5900 3050);
FORCEPROP 1 LASTPIN (-5900 2950) $PN 2
J 0
(-5890 2930);
DISPLAY 0.617021 (-5890 2930);
PAINT GREEN (-5890 2930);
FORCEPROP 1 LASTPIN (-5900 3150) $PN 1
J 0
(-5890 3130);
DISPLAY 0.617021 (-5890 3130);
PAINT GREEN (-5890 3130);
FORCEPROP 1 LAST VOLTAGE 4V
J 0
(-5850 3100);
DISPLAY 0.617021 (-5850 3100);
PAINT SKYBLUE (-5850 3100);
FORCEPROP 1 LAST MATERIAL X6S
J 0
(-5850 3000);
DISPLAY 0.617021 (-5850 3000);
PAINT SKYBLUE (-5850 3000);
FORCEPROP 1 LAST PACK_TYPE 0603V
J 0
(-5850 2900);
DISPLAY 0.617021 (-5850 2900);
PAINT SKYBLUE (-5850 2900);
FORCEPROP 1 LAST PART_NUMBER E15431-004
J 0
(-5850 2950);
DISPLAY 0.617021 (-5850 2950);
PAINT BLUE (-5850 2950);
FORCEPROP 1 LAST VALUE 22.0UF
J 0
(-5850 3150);
DISPLAY 0.617021 (-5850 3150);
PAINT SKYBLUE (-5850 3150);
FORCEPROP 1 LAST LOCATION C2D32
J 0
(-5850 3200);
DISPLAY 0.617021 (-5850 3200);
PAINT AQUA (-5850 3200);
FORCEPROP 0 LAST GROUP PWR_MLCC_CAP
J 0
(-5844 2862);
DISPLAY 0.638298 (-5844 2862);
PAINT BROWN (-5844 2862);
DISPLAY BOTH (-5844 2862);
FORCEPROP 1 LAST TOLERANCE 20%
J 0
(-5850 3050);
DISPLAY 0.617021 (-5850 3050);
PAINT SKYBLUE (-5850 3050);
FORCEPROP 2 LAST ROOM PVCCIN_CPU1_DECAP_VR
J 0
(-5850 3150);
PAINT ORANGE (-5850 3150);
DISPLAY INVISIBLE (-5850 3150);
FORCEPROP 1 LAST PATH I90
J 0
(-5850 3200);
DISPLAY 0.978723 (-5850 3200);
PAINT WHITE (-5850 3200);
DISPLAY INVISIBLE (-5850 3200);
FORCEPROP 2 LAST $SEC 1
J 0
(-5850 3250);
PAINT MONO (-5850 3250);
DISPLAY INVISIBLE (-5850 3250);
FORCEPROP 2 LAST CDS_SEC 1
J 0
(-5850 3250);
PAINT MONO (-5850 3250);
DISPLAY INVISIBLE (-5850 3250);
FORCEPROP 2 LAST CDS_LIB dev_discrete
J 0
(-5900 3050);
PAINT ORANGE (-5900 3050);
DISPLAY INVISIBLE (-5900 3050);
FORCEPROP 2 LAST BOM_COST PROC
J 0
(-5900 3050);
PAINT MONO (-5900 3050);
DISPLAY INVISIBLE (-5900 3050);
FORCEPROP 2 LAST CDS_LOCATION C2D32
J 0
(-5850 3150);
DISPLAY 0.617021 (-5850 3150);
PAINT AQUA (-5850 3150);
DISPLAY INVISIBLE (-5850 3150);
FORCEADD CAP..1
(-5950 2200);
FORCEPROP 1 LAST VOLTAGE 4V
J 0
(-5900 2250);
DISPLAY 0.638298 (-5900 2250);
PAINT SKYBLUE (-5900 2250);
FORCEPROP 1 LAST VALUE 47UF
J 0
(-5900 2300);
DISPLAY 0.617021 (-5900 2300);
PAINT SKYBLUE (-5900 2300);
FORCEPROP 1 LAST PACK_TYPE 0805
J 0
(-5900 2100);
DISPLAY 0.617021 (-5900 2100);
PAINT SKYBLUE (-5900 2100);
FORCEPROP 1 LASTPIN (-5950 2100) $PN 2
J 0
(-5940 2080);
DISPLAY 0.617021 (-5940 2080);
PAINT GREEN (-5940 2080);
FORCEPROP 1 LAST LOCATION C8P18
J 0
(-5900 2350);
DISPLAY 0.617021 (-5900 2350);
PAINT AQUA (-5900 2350);
FORCEPROP 1 LAST MATERIAL X6S
J 0
(-5900 2150);
DISPLAY 0.638298 (-5900 2150);
PAINT SKYBLUE (-5900 2150);
FORCEPROP 1 LASTPIN (-5950 2300) $PN 1
J 0
(-5940 2280);
DISPLAY 0.617021 (-5940 2280);
PAINT GREEN (-5940 2280);
FORCEPROP 1 LAST TOLERANCE 20%
J 0
(-5900 2200);
DISPLAY 0.617021 (-5900 2200);
PAINT SKYBLUE (-5900 2200);
FORCEPROP 0 LAST GROUP PWR_MLCC_CAP
J 0
(-5894 2037);
DISPLAY 0.638298 (-5894 2037);
PAINT BROWN (-5894 2037);
DISPLAY BOTH (-5894 2037);
FORCEPROP 1 LAST PART_NUMBER C95333-006
R 1
J 0
(-6000 2100);
DISPLAY 0.617021 (-6000 2100);
PAINT BLUE (-6000 2100);
FORCEPROP 2 LAST BOM_COST PROC
J 0
(-5950 2200);
PAINT MONO (-5950 2200);
DISPLAY INVISIBLE (-5950 2200);
FORCEPROP 2 LAST CDS_LIB mstr_discrete
J 0
(-5950 2200);
PAINT ORANGE (-5950 2200);
DISPLAY INVISIBLE (-5950 2200);
FORCEPROP 2 LAST CDS_SEC 1
J 0
(-5900 2400);
DISPLAY 1.021277 (-5900 2400);
PAINT ORANGE (-5900 2400);
DISPLAY INVISIBLE (-5900 2400);
FORCEPROP 2 LAST $SEC 1
J 0
(-5900 2400);
DISPLAY 0.680851 (-5900 2400);
PAINT MONO (-5900 2400);
DISPLAY INVISIBLE (-5900 2400);
FORCEPROP 2 LAST CDS_LOCATION C8P18
J 0
(-5900 2300);
DISPLAY 0.617021 (-5900 2300);
PAINT AQUA (-5900 2300);
DISPLAY INVISIBLE (-5900 2300);
FORCEPROP 1 LAST PATH I92
J 0
(-5900 2350);
DISPLAY 0.978723 (-5900 2350);
PAINT WHITE (-5900 2350);
DISPLAY INVISIBLE (-5900 2350);
FORCEPROP 2 LAST ROOM PVCCIN_CPU1_DECAP_VR
J 0
(-5900 2300);
PAINT ORANGE (-5900 2300);
DISPLAY INVISIBLE (-5900 2300);
FORCEADD INTEL_CORP_BPAGE..1
(0 0);
FORCEPROP 1 LAST CDS_CON_LAST_MODIFIED Fri Jun 16 17:48:28 2017
J 0
(-1425 325);
PAINT ORANGE (-1425 325);
DISPLAY INVISIBLE (-1425 325);
FORCEPROP 1 LAST CUSTOM_TXT_CDS <CURRENT_DESIGN_SHEET> OF <TOTAL_DESIGN_SHEETS>
J 0
(-500 25);
PAINT ORANGE (-500 25);
FORCEPROP 1 LAST CUSTOM_TXT_CDS <CON_LAST_MODIFIED>
J 0
(-4000 100);
PAINT ORANGE (-4000 100);
FORCEPROP 2 LAST CUSTOM_TXT_CDS <XR_PAGE_TITLE>
J 0
(-7890 5250);
DISPLAY 0.638298 (-7890 5250);
PAINT PINK (-7890 5250);
DISPLAY INVISIBLE (-7890 5250);
FORCEPROP 1 LAST SCH_TITLE CPU1 DECOUPLING CAVITY CAPS
J 0
(-7950 50);
DISPLAY 1.212766 (-7950 50);
PAINT ORANGE (-7950 50);
FORCEPROP 2 LAST CDS_XR_PAGE_TITLE CR-76 : @BASEBOARD_FAB2_LIB.BASEBOARD_FAB2(SCH_1):PAGE76
J 0
(-7890 5250);
DISPLAY 0.638298 (-7890 5250);
PAINT PINK (-7890 5250);
DISPLAY INVISIBLE (-7890 5250);
FORCEPROP 2 LAST PAGE_BORDER TRUE
J 0
(-7890 5250);
DISPLAY 0.638298 (-7890 5250);
PAINT PINK (-7890 5250);
DISPLAY INVISIBLE (-7890 5250);
FORCEPROP 2 LAST CDS_LIB mstr_symbols
J 0
(0 0);
PAINT MONO (0 0);
DISPLAY INVISIBLE (0 0);
FORCEPROP 1 LAST COMMENT_BODY TRUE
J 0
(12 12);
DISPLAY 0.468085 (12 12);
PAINT GREEN (12 12);
DISPLAY INVISIBLE (12 12);
FORCEADD DESIGN_NOTE..1
(-2400 3250);
PAINT PURPLE (-2400 3250);
FORCEPROP 0 LAST L3 * TO BE PLACED IN
J 0
(-2600 3000);
PAINT VIOLET (-2600 3000);
FORCEPROP 0 LAST L4 SKT 0 CAVITY (TOP)
J 0
(-2600 2950);
PAINT VIOLET (-2600 2950);
FORCEPROP 0 LAST L1 * HIGH TEMPERATURE
J 0
(-2600 3125);
PAINT VIOLET (-2600 3125);
FORCEPROP 0 LAST L2 CAPACITORS.
J 0
(-2600 3075);
PAINT VIOLET (-2600 3075);
FORCEPROP 2 LAST CDS_LIB mstr_symbols
J 0
(-2400 3250);
PAINT MONO (-2400 3250);
DISPLAY INVISIBLE (-2400 3250);
FORCEPROP 2 LAST BOM_COST SM_CONTROLLER
J 0
(-2600 3200);
PAINT MONO (-2600 3200);
DISPLAY INVISIBLE (-2600 3200);
FORCEPROP 1 LAST COMMENT_BODY TRUE
J 0
(-2375 3350);
DISPLAY 1.319149 (-2375 3350);
PAINT GREEN (-2375 3350);
DISPLAY INVISIBLE (-2375 3350);
FORCEPROP 2 LAST ROOM PVCCIN_CPU1_DECAP_VR
J 0
(-2600 3200);
PAINT MONO (-2600 3200);
DISPLAY INVISIBLE (-2600 3200);
FORCEADD DESIGN_NOTE..1
(-1200 850);
PAINT PURPLE (-1200 850);
FORCEPROP 0 LAST L1 * HIGH TEMPERATURE
J 0
(-1400 725);
PAINT VIOLET (-1400 725);
FORCEPROP 0 LAST L4 SKT 0 CAVITY (BOTTOM)
J 0
(-1400 550);
PAINT VIOLET (-1400 550);
FORCEPROP 0 LAST L3 * TO BE PLACED IN
J 0
(-1400 600);
PAINT VIOLET (-1400 600);
FORCEPROP 0 LAST L2 CAPACITORS.
J 0
(-1400 675);
PAINT VIOLET (-1400 675);
FORCEPROP 2 LAST ROOM PVCCIN_CPU1_DECAP_VR
J 0
(-1400 800);
PAINT MONO (-1400 800);
DISPLAY INVISIBLE (-1400 800);
FORCEPROP 1 LAST COMMENT_BODY TRUE
J 0
(-1175 950);
DISPLAY 1.319149 (-1175 950);
PAINT GREEN (-1175 950);
DISPLAY INVISIBLE (-1175 950);
FORCEPROP 2 LAST BOM_COST SM_CONTROLLER
J 0
(-1400 800);
PAINT MONO (-1400 800);
DISPLAY INVISIBLE (-1400 800);
FORCEPROP 2 LAST CDS_LIB mstr_symbols
J 0
(-1200 850);
PAINT MONO (-1200 850);
DISPLAY INVISIBLE (-1200 850);
WIRE 16 -1 (-7750 3525)(-7750 3550);
WIRE 16 -1 (-7750 3550)(-7450 3550);
WIRE 16 -1 (-7750 3650)(-7750 3550);
WIRE 16 -1 (-6750 3550)(-7450 3550);
WIRE 16 -1 (-7450 3650)(-7450 3550);
WIRE 16 -1 (-6750 3650)(-6750 3550);
WIRE 16 -1 (-7750 2825)(-7750 2850);
WIRE 16 -1 (-7750 2850)(-7050 2850);
WIRE 16 -1 (-7750 2950)(-7750 2850);
WIRE 16 -1 (-6750 2850)(-7050 2850);
WIRE 16 -1 (-7050 2950)(-7050 2850);
WIRE 16 -1 (-6750 2950)(-6750 2850);
WIRE 16 -1 (-6550 1275)(-6550 1400);
WIRE 16 -1 (-7750 575)(-7750 600);
WIRE 16 -1 (-7450 600)(-7750 600);
WIRE 16 -1 (-7750 700)(-7750 600);
WIRE 16 -1 (-7150 600)(-7450 600);
WIRE 16 -1 (-7450 700)(-7450 600);
WIRE 16 -1 (-6850 600)(-7150 600);
WIRE 16 -1 (-7150 700)(-7150 600);
WIRE 16 -1 (-6550 600)(-6850 600);
WIRE 16 -1 (-6850 700)(-6850 600);
WIRE 16 -1 (-6550 700)(-6550 600);
WIRE 16 -1 (-5900 4650)(-5900 4700);
WIRE 16 -1 (-5600 4650)(-5900 4650);
WIRE 16 -1 (-5900 4650)(-5900 4550);
WIRE 16 -1 (-5100 4650)(-5600 4650);
WIRE 16 -1 (-5600 4550)(-5600 4650);
WIRE 16 -1 (-4800 4650)(-5100 4650);
WIRE 16 -1 (-5100 4550)(-5100 4650);
WIRE 16 -1 (-4500 4650)(-4800 4650);
WIRE 16 -1 (-4800 4650)(-4800 4550);
WIRE 16 -1 (-4500 4650)(-4500 4550);
WIRE 16 -1 (-7750 3950)(-7750 4000);
WIRE 16 -1 (-7450 3950)(-7750 3950);
WIRE 16 -1 (-7750 3950)(-7750 3850);
WIRE 16 -1 (-6750 3950)(-7450 3950);
WIRE 16 -1 (-7450 3850)(-7450 3950);
WIRE 16 -1 (-6750 3950)(-6750 3850);
WIRE 16 -1 (-7750 3250)(-7750 3300);
WIRE 16 -1 (-7050 3250)(-7750 3250);
WIRE 16 -1 (-7750 3250)(-7750 3150);
WIRE 16 -1 (-6750 3250)(-7050 3250);
WIRE 16 -1 (-7050 3150)(-7050 3250);
WIRE 16 -1 (-6750 3250)(-6750 3150);
WIRE 16 -1 (-5900 3950)(-5900 4000);
WIRE 16 -1 (-5600 3950)(-5900 3950);
WIRE 16 -1 (-5900 3950)(-5900 3850);
WIRE 16 -1 (-5300 3950)(-5600 3950);
WIRE 16 -1 (-5600 3850)(-5600 3950);
WIRE 16 -1 (-5000 3950)(-5300 3950);
WIRE 16 -1 (-5300 3850)(-5300 3950);
WIRE 16 -1 (-4700 3950)(-5000 3950);
WIRE 16 -1 (-5000 3850)(-5000 3950);
WIRE 16 -1 (-4400 3950)(-4700 3950);
WIRE 16 -1 (-4700 3950)(-4700 3850);
WIRE 16 -1 (-4400 3950)(-4400 3850);
WIRE 16 -1 (-5900 3300)(-5900 3250);
WIRE 16 -1 (-5400 3250)(-5900 3250);
WIRE 16 -1 (-5900 3250)(-5900 3150);
WIRE 16 -1 (-5100 3250)(-5400 3250);
WIRE 16 -1 (-5400 3150)(-5400 3250);
WIRE 16 -1 (-4800 3250)(-5100 3250);
WIRE 16 -1 (-5100 3150)(-5100 3250);
WIRE 16 -1 (-4500 3250)(-4800 3250);
WIRE 16 -1 (-4800 3250)(-4800 3150);
WIRE 16 -1 (-4500 3250)(-4500 3150);
WIRE 16 -1 (-5950 2400)(-5950 2450);
WIRE 16 -1 (-5950 2400)(-5650 2400);
WIRE 16 -1 (-5950 2400)(-5950 2300);
WIRE 16 -1 (-5650 2300)(-5650 2400);
WIRE 16 -1 (-7750 2400)(-7750 2450);
WIRE 16 -1 (-7450 2400)(-7750 2400);
WIRE 16 -1 (-7750 2300)(-7750 2400);
WIRE 16 -1 (-7150 2400)(-7450 2400);
WIRE 16 -1 (-7450 2300)(-7450 2400);
WIRE 16 -1 (-6850 2400)(-7150 2400);
WIRE 16 -1 (-7150 2300)(-7150 2400);
WIRE 16 -1 (-6850 2300)(-6850 2400);
WIRE 16 -1 (-7750 1750)(-7750 1700);
WIRE 16 -1 (-7450 1700)(-7750 1700);
WIRE 16 -1 (-7750 1700)(-7750 1600);
WIRE 16 -1 (-7150 1700)(-7450 1700);
WIRE 16 -1 (-7450 1600)(-7450 1700);
WIRE 16 -1 (-7150 1600)(-7150 1700);
WIRE 16 -1 (-5950 1600)(-5950 1750);
WIRE 16 -1 (-5950 900)(-5950 1050);
WIRE 16 -1 (-7750 1050)(-7750 1000);
WIRE 16 -1 (-7450 1000)(-7750 1000);
WIRE 16 -1 (-7750 900)(-7750 1000);
WIRE 16 -1 (-7150 1000)(-7450 1000);
WIRE 16 -1 (-7450 900)(-7450 1000);
WIRE 16 -1 (-6850 1000)(-7150 1000);
WIRE 16 -1 (-7150 900)(-7150 1000);
WIRE 16 -1 (-6850 1000)(-6550 1000);
WIRE 16 -1 (-6850 900)(-6850 1000);
WIRE 16 -1 (-6550 1000)(-6550 900);
WIRE 16 -1 (-3850 3525)(-3850 3550);
WIRE 16 -1 (-3850 3550)(-3550 3550);
WIRE 16 -1 (-3850 3650)(-3850 3550);
WIRE 16 -1 (-3550 3550)(-3250 3550);
WIRE 16 -1 (-3550 3650)(-3550 3550);
WIRE 16 -1 (-2950 3550)(-3250 3550);
WIRE 16 -1 (-3250 3650)(-3250 3550);
WIRE 16 -1 (-2650 3550)(-2950 3550);
WIRE 16 -1 (-2950 3650)(-2950 3550);
WIRE 16 -1 (-2350 3550)(-2650 3550);
WIRE 16 -1 (-2650 3650)(-2650 3550);
WIRE 16 -1 (-2350 3650)(-2350 3550);
WIRE 16 -1 (-4000 4625)(-4000 4675);
WIRE 16 -1 (-3750 4625)(-4000 4625);
WIRE 16 -1 (-4000 4625)(-4000 4550);
WIRE 16 -1 (-3500 4625)(-3750 4625);
WIRE 16 -1 (-3750 4550)(-3750 4625);
WIRE 16 -1 (-3250 4625)(-3500 4625);
WIRE 16 -1 (-3500 4550)(-3500 4625);
WIRE 16 -1 (-2975 4625)(-3250 4625);
WIRE 16 -1 (-3250 4550)(-3250 4625);
WIRE 16 -1 (-2725 4625)(-2975 4625);
WIRE 16 -1 (-2975 4625)(-2975 4550);
WIRE 16 -1 (-2450 4625)(-2725 4625);
WIRE 16 -1 (-2725 4550)(-2725 4625);
WIRE 16 -1 (-2175 4625)(-2450 4625);
WIRE 16 -1 (-2450 4625)(-2450 4550);
WIRE 16 -1 (-1875 4625)(-2175 4625);
WIRE 16 -1 (-2175 4550)(-2175 4625);
WIRE 16 -1 (-1600 4625)(-1875 4625);
WIRE 16 -1 (-1875 4550)(-1875 4625);
WIRE 16 -1 (-1275 4625)(-1600 4625);
WIRE 16 -1 (-1600 4550)(-1600 4625);
WIRE 16 -1 (-975 4625)(-1275 4625);
WIRE 16 -1 (-1275 4625)(-1275 4550);
WIRE 16 -1 (-725 4625)(-975 4625);
WIRE 16 -1 (-975 4625)(-975 4550);
WIRE 16 -1 (-725 4550)(-725 4625);
WIRE 16 -1 (-4600 2400)(-4600 2425);
WIRE 16 -1 (-4350 2400)(-4600 2400);
WIRE 16 -1 (-4600 2300)(-4600 2400);
WIRE 16 -1 (-4100 2400)(-4350 2400);
WIRE 16 -1 (-4350 2300)(-4350 2400);
WIRE 16 -1 (-4100 2400)(-3850 2400);
WIRE 16 -1 (-4100 2300)(-4100 2400);
WIRE 16 -1 (-3600 2400)(-3850 2400);
WIRE 16 -1 (-3850 2300)(-3850 2400);
WIRE 16 -1 (-3600 2400)(-3350 2400);
WIRE 16 -1 (-3600 2300)(-3600 2400);
WIRE 16 -1 (-3100 2400)(-3350 2400);
WIRE 16 -1 (-3350 2300)(-3350 2400);
WIRE 16 -1 (-2850 2400)(-3100 2400);
WIRE 16 -1 (-3100 2300)(-3100 2400);
WIRE 16 -1 (-2600 2400)(-2850 2400);
WIRE 16 -1 (-2850 2400)(-2850 2300);
WIRE 16 -1 (-2350 2400)(-2600 2400);
WIRE 16 -1 (-2600 2300)(-2600 2400);
WIRE 16 -1 (-2100 2400)(-2350 2400);
WIRE 16 -1 (-2350 2300)(-2350 2400);
WIRE 16 -1 (-2100 2400)(-1850 2400);
WIRE 16 -1 (-2100 2300)(-2100 2400);
WIRE 16 -1 (-1600 2400)(-1850 2400);
WIRE 16 -1 (-1850 2400)(-1850 2300);
WIRE 16 -1 (-1600 2400)(-1350 2400);
WIRE 16 -1 (-1600 2300)(-1600 2400);
WIRE 16 -1 (-1100 2400)(-1350 2400);
WIRE 16 -1 (-1350 2300)(-1350 2400);
WIRE 16 -1 (-1100 2400)(-850 2400);
WIRE 16 -1 (-1100 2300)(-1100 2400);
WIRE 16 -1 (-600 2400)(-850 2400);
WIRE 16 -1 (-850 2300)(-850 2400);
WIRE 16 -1 (-600 2400)(-600 2300);
WIRE 16 -1 (-3850 3950)(-3850 4000);
WIRE 16 -1 (-3850 3950)(-3550 3950);
WIRE 16 -1 (-3850 3950)(-3850 3850);
WIRE 16 -1 (-3250 3950)(-3550 3950);
WIRE 16 -1 (-3550 3850)(-3550 3950);
WIRE 16 -1 (-2950 3950)(-3250 3950);
WIRE 16 -1 (-3250 3850)(-3250 3950);
WIRE 16 -1 (-2650 3950)(-2950 3950);
WIRE 16 -1 (-2950 3950)(-2950 3850);
WIRE 16 -1 (-2350 3950)(-2650 3950);
WIRE 16 -1 (-2650 3850)(-2650 3950);
WIRE 16 -1 (-2350 3850)(-2350 3950);
WIRE 16 -1 (-725 4150)(-725 4250);
WIRE 16 -1 (-725 4250)(-975 4250);
WIRE 16 -1 (-725 4350)(-725 4250);
WIRE 16 -1 (-975 4250)(-1275 4250);
WIRE 16 -1 (-975 4350)(-975 4250);
WIRE 16 -1 (-1275 4250)(-1600 4250);
WIRE 16 -1 (-1275 4350)(-1275 4250);
WIRE 16 -1 (-1600 4250)(-1875 4250);
WIRE 16 -1 (-1600 4350)(-1600 4250);
WIRE 16 -1 (-1875 4250)(-2175 4250);
WIRE 16 -1 (-1875 4350)(-1875 4250);
WIRE 16 -1 (-2175 4250)(-2450 4250);
WIRE 16 -1 (-2175 4350)(-2175 4250);
WIRE 16 -1 (-2450 4250)(-2725 4250);
WIRE 16 -1 (-2450 4350)(-2450 4250);
WIRE 16 -1 (-2725 4250)(-2975 4250);
WIRE 16 -1 (-2725 4350)(-2725 4250);
WIRE 16 -1 (-2975 4250)(-3250 4250);
WIRE 16 -1 (-2975 4350)(-2975 4250);
WIRE 16 -1 (-3250 4250)(-3500 4250);
WIRE 16 -1 (-3250 4350)(-3250 4250);
WIRE 16 -1 (-3500 4250)(-3750 4250);
WIRE 16 -1 (-3500 4350)(-3500 4250);
WIRE 16 -1 (-4000 4250)(-3750 4250);
WIRE 16 -1 (-3750 4350)(-3750 4250);
WIRE 16 -1 (-4000 4350)(-4000 4250);
WIRE 16 -1 (-1975 3975)(-1975 3950);
WIRE 16 -1 (-1725 3950)(-1975 3950);
WIRE 16 -1 (-1975 3950)(-1975 3875);
WIRE 16 -1 (-1475 3950)(-1725 3950);
WIRE 16 -1 (-1725 3875)(-1725 3950);
WIRE 16 -1 (-1225 3950)(-1475 3950);
WIRE 16 -1 (-1475 3875)(-1475 3950);
WIRE 16 -1 (-1225 3950)(-975 3950);
WIRE 16 -1 (-1225 3875)(-1225 3950);
WIRE 16 -1 (-750 3950)(-975 3950);
WIRE 16 -1 (-975 3875)(-975 3950);
WIRE 16 -1 (-750 3875)(-750 3950);
WIRE 16 -1 (-750 3500)(-750 3550);
WIRE 16 -1 (-975 3550)(-750 3550);
WIRE 16 -1 (-750 3675)(-750 3550);
WIRE 16 -1 (-1225 3550)(-975 3550);
WIRE 16 -1 (-975 3675)(-975 3550);
WIRE 16 -1 (-1475 3550)(-1225 3550);
WIRE 16 -1 (-1225 3675)(-1225 3550);
WIRE 16 -1 (-1725 3550)(-1475 3550);
WIRE 16 -1 (-1475 3675)(-1475 3550);
WIRE 16 -1 (-1975 3550)(-1725 3550);
WIRE 16 -1 (-1725 3675)(-1725 3550);
WIRE 16 -1 (-1975 3675)(-1975 3550);
WIRE 16 -1 (-5950 575)(-5950 700);
WIRE 16 -1 (-7750 1300)(-7750 1275);
WIRE 16 -1 (-7750 1300)(-7450 1300);
WIRE 16 -1 (-7750 1400)(-7750 1300);
WIRE 16 -1 (-7150 1300)(-7450 1300);
WIRE 16 -1 (-7450 1400)(-7450 1300);
WIRE 16 -1 (-7150 1400)(-7150 1300);
WIRE 16 -1 (-6550 1750)(-6550 1600);
WIRE 16 -1 (-7750 2000)(-7750 1975);
WIRE 16 -1 (-7450 2000)(-7750 2000);
WIRE 16 -1 (-7750 2100)(-7750 2000);
WIRE 16 -1 (-7150 2000)(-7450 2000);
WIRE 16 -1 (-7450 2100)(-7450 2000);
WIRE 16 -1 (-6850 2000)(-7150 2000);
WIRE 16 -1 (-7150 2100)(-7150 2000);
WIRE 16 -1 (-6850 2100)(-6850 2000);
WIRE 16 -1 (-5950 2000)(-5950 1975);
WIRE 16 -1 (-5950 2000)(-5650 2000);
WIRE 16 -1 (-5950 2100)(-5950 2000);
WIRE 16 -1 (-5650 2100)(-5650 2000);
WIRE 16 -1 (-4600 2025)(-4600 2050);
WIRE 16 -1 (-4600 2050)(-4350 2050);
WIRE 16 -1 (-4600 2100)(-4600 2050);
WIRE 16 -1 (-4350 2050)(-4100 2050);
WIRE 16 -1 (-4350 2100)(-4350 2050);
WIRE 16 -1 (-3850 2050)(-4100 2050);
WIRE 16 -1 (-4100 2100)(-4100 2050);
WIRE 16 -1 (-3850 2050)(-3600 2050);
WIRE 16 -1 (-3850 2100)(-3850 2050);
WIRE 16 -1 (-3600 2050)(-3350 2050);
WIRE 16 -1 (-3600 2100)(-3600 2050);
WIRE 16 -1 (-3100 2050)(-3350 2050);
WIRE 16 -1 (-3350 2100)(-3350 2050);
WIRE 16 -1 (-3100 2050)(-2850 2050);
WIRE 16 -1 (-3100 2100)(-3100 2050);
WIRE 16 -1 (-2600 2050)(-2850 2050);
WIRE 16 -1 (-2850 2100)(-2850 2050);
WIRE 16 -1 (-2350 2050)(-2600 2050);
WIRE 16 -1 (-2600 2100)(-2600 2050);
WIRE 16 -1 (-2350 2050)(-2100 2050);
WIRE 16 -1 (-2350 2100)(-2350 2050);
WIRE 16 -1 (-2100 2050)(-1850 2050);
WIRE 16 -1 (-2100 2100)(-2100 2050);
WIRE 16 -1 (-1850 2050)(-1600 2050);
WIRE 16 -1 (-1850 2100)(-1850 2050);
WIRE 16 -1 (-1600 2050)(-1350 2050);
WIRE 16 -1 (-1600 2100)(-1600 2050);
WIRE 16 -1 (-1350 2050)(-1100 2050);
WIRE 16 -1 (-1350 2100)(-1350 2050);
WIRE 16 -1 (-1100 2050)(-850 2050);
WIRE 16 -1 (-1100 2100)(-1100 2050);
WIRE 16 -1 (-600 2050)(-850 2050);
WIRE 16 -1 (-850 2100)(-850 2050);
WIRE 16 -1 (-600 2100)(-600 2050);
WIRE 16 -1 (-5950 1275)(-5950 1400);
WIRE 16 -1 (-1200 1200)(-1200 1100);
WIRE 16 -1 (-1200 1500)(-1200 1400);
WIRE 16 -1 (-1100 2825)(-1100 2850);
WIRE 16 -1 (-1400 2850)(-1100 2850);
WIRE 16 -1 (-1100 2850)(-1100 2950);
WIRE 16 -1 (-1400 2950)(-1400 2850);
WIRE 16 -1 (-1400 3275)(-1400 3250);
WIRE 16 -1 (-1400 3250)(-1100 3250);
WIRE 16 -1 (-1400 3250)(-1400 3150);
WIRE 16 -1 (-1100 3250)(-1100 3150);
WIRE 16 -1 (-3300 825)(-3300 850);
WIRE 16 -1 (-3300 850)(-3000 850);
WIRE 16 -1 (-3300 1050)(-3300 850);
WIRE 16 -1 (-2700 850)(-3000 850);
WIRE 16 -1 (-3000 1050)(-3000 850);
WIRE 16 -1 (-2400 850)(-2700 850);
WIRE 16 -1 (-2700 1050)(-2700 850);
WIRE 16 -1 (-2100 850)(-2400 850);
WIRE 16 -1 (-2400 1050)(-2400 850);
WIRE 16 -1 (-2100 1050)(-2100 850);
WIRE 16 -1 (-3950 2825)(-3950 2850);
WIRE 16 -1 (-3950 2850)(-3650 2850);
WIRE 16 -1 (-3950 3000)(-3950 2850);
WIRE 16 -1 (-3350 2850)(-3650 2850);
WIRE 16 -1 (-3650 3000)(-3650 2850);
WIRE 16 -1 (-3050 2850)(-3350 2850);
WIRE 16 -1 (-3350 3000)(-3350 2850);
WIRE 16 -1 (-3050 2850)(-3050 3000);
WIRE 16 -1 (-3950 3350)(-3950 3300);
WIRE 16 -1 (-3950 3300)(-3650 3300);
WIRE 16 -1 (-3950 3200)(-3950 3300);
WIRE 16 -1 (-3350 3300)(-3650 3300);
WIRE 16 -1 (-3650 3200)(-3650 3300);
WIRE 16 -1 (-3050 3300)(-3350 3300);
WIRE 16 -1 (-3350 3200)(-3350 3300);
WIRE 16 -1 (-3050 3300)(-3050 3200);
WIRE 16 -1 (-3300 1350)(-3300 1400);
WIRE 16 -1 (-3300 1350)(-3000 1350);
WIRE 16 -1 (-3300 1250)(-3300 1350);
WIRE 16 -1 (-2700 1350)(-3000 1350);
WIRE 16 -1 (-3000 1250)(-3000 1350);
WIRE 16 -1 (-2400 1350)(-2700 1350);
WIRE 16 -1 (-2700 1250)(-2700 1350);
WIRE 16 -1 (-2100 1350)(-2400 1350);
WIRE 16 -1 (-2400 1250)(-2400 1350);
WIRE 16 -1 (-2100 1350)(-2100 1250);
WIRE 16 -1 (-3950 825)(-3950 850);
WIRE 16 -1 (-3950 850)(-4250 850);
WIRE 16 -1 (-3950 1050)(-3950 850);
WIRE 16 -1 (-4550 850)(-4250 850);
WIRE 16 -1 (-4250 1050)(-4250 850);
WIRE 16 -1 (-4550 1050)(-4550 850);
WIRE 16 -1 (-4550 1400)(-4550 1350);
WIRE 16 -1 (-4550 1350)(-4250 1350);
WIRE 16 -1 (-4550 1250)(-4550 1350);
WIRE 16 -1 (-3950 1350)(-4250 1350);
WIRE 16 -1 (-4250 1250)(-4250 1350);
WIRE 16 -1 (-3950 1250)(-3950 1350);
WIRE 16 -1 (-5900 4225)(-5900 4250);
WIRE 16 -1 (-5900 4250)(-5600 4250);
WIRE 16 -1 (-5900 4350)(-5900 4250);
WIRE 16 -1 (-5100 4250)(-5600 4250);
WIRE 16 -1 (-5600 4350)(-5600 4250);
WIRE 16 -1 (-4800 4250)(-5100 4250);
WIRE 16 -1 (-5100 4350)(-5100 4250);
WIRE 16 -1 (-4500 4250)(-4800 4250);
WIRE 16 -1 (-4800 4350)(-4800 4250);
WIRE 16 -1 (-4500 4350)(-4500 4250);
WIRE 16 -1 (-7750 4225)(-7750 4250);
WIRE 16 -1 (-7750 4250)(-7650 4250);
WIRE 16 -1 (-7650 4250)(-7350 4250);
WIRE 16 -1 (-7650 4350)(-7650 4250);
WIRE 16 -1 (-7350 4250)(-6650 4250);
WIRE 16 -1 (-7350 4350)(-7350 4250);
WIRE 16 -1 (-6650 4350)(-6650 4250);
WIRE 16 -1 (-7750 4650)(-7750 4700);
WIRE 16 -1 (-7750 4650)(-7650 4650);
WIRE 16 -1 (-7350 4650)(-7650 4650);
WIRE 16 -1 (-7650 4550)(-7650 4650);
WIRE 16 -1 (-6650 4650)(-7350 4650);
WIRE 16 -1 (-7350 4550)(-7350 4650);
WIRE 16 -1 (-6650 4650)(-6650 4550);
WIRE 16 -1 (-5900 3525)(-5900 3550);
WIRE 16 -1 (-5900 3550)(-5600 3550);
WIRE 16 -1 (-5900 3650)(-5900 3550);
WIRE 16 -1 (-5300 3550)(-5600 3550);
WIRE 16 -1 (-5600 3650)(-5600 3550);
WIRE 16 -1 (-5000 3550)(-5300 3550);
WIRE 16 -1 (-5300 3650)(-5300 3550);
WIRE 16 -1 (-4700 3550)(-5000 3550);
WIRE 16 -1 (-5000 3650)(-5000 3550);
WIRE 16 -1 (-4400 3550)(-4700 3550);
WIRE 16 -1 (-4700 3650)(-4700 3550);
WIRE 16 -1 (-4400 3650)(-4400 3550);
WIRE 16 -1 (-5900 2825)(-5900 2850);
WIRE 16 -1 (-5400 2850)(-5900 2850);
WIRE 16 -1 (-5900 2950)(-5900 2850);
WIRE 16 -1 (-5100 2850)(-5400 2850);
WIRE 16 -1 (-5400 2950)(-5400 2850);
WIRE 16 -1 (-4800 2850)(-5100 2850);
WIRE 16 -1 (-5100 2950)(-5100 2850);
WIRE 16 -1 (-4500 2850)(-4800 2850);
WIRE 16 -1 (-4800 2950)(-4800 2850);
WIRE 16 -1 (-4500 2950)(-4500 2850);
WIRE 3 682 (-100 2600)(-4800 2600);
WIRE 3 682 (-100 1700)(-100 2600);
WIRE 3 682 (-4800 2600)(-4800 1700);
WIRE 3 682 (-4800 1700)(-100 1700);
WIRE 16 2175 (-7900 400)(-7900 2625);
WIRE 16 2175 (-50 400)(-7900 400);
WIRE 16 2175 (-7900 2625)(-50 2625);
WIRE 16 2175 (-50 2625)(-50 400);
WIRE 16 2175 (-100 2675)(-7925 2675);
WIRE 16 2175 (-100 4850)(-100 2675);
WIRE 16 2175 (-7925 2675)(-7925 4850);
WIRE 16 2175 (-7925 4850)(-100 4850);
WIRE 3 682 (-1400 1650)(-1400 1000);
WIRE 3 682 (-600 1650)(-1400 1650);
WIRE 3 682 (-1400 1000)(-600 1000);
WIRE 3 682 (-600 1000)(-600 1650);
WIRE 3 682 (-5200 2350)(-5200 2100);
WIRE 3 682 (-5150 2350)(-5200 2350);
WIRE 3 682 (-5150 2350)(-5150 2450);
WIRE 3 682 (-5025 2350)(-5150 2350);
WIRE 3 682 (-5200 2100)(-5025 2100);
WIRE 3 682 (-5025 2100)(-5025 2350);
WIRE 3 682 (-1550 3450)(-1550 2750);
WIRE 3 682 (-800 3450)(-1550 3450);
WIRE 3 682 (-1550 2750)(-800 2750);
WIRE 3 682 (-800 2750)(-800 3450);
WIRE 3 682 (-5600 2550)(-5575 2550);
WIRE 3 682 (-5600 2400)(-5600 2550);
WIRE 3 682 (-5400 2400)(-5600 2400);
WIRE 3 682 (-5400 2350)(-5400 2400);
WIRE 3 682 (-5400 2350)(-5450 2350);
WIRE 3 682 (-5250 2350)(-5400 2350);
WIRE 3 682 (-5250 2100)(-5250 2350);
WIRE 3 682 (-5450 2350)(-5450 2100);
WIRE 3 682 (-5450 2100)(-5250 2100);
WIRE 3 682 (-7800 4300)(-7700 4300);
WIRE 3 682 (-7800 4600)(-7800 4300);
WIRE 3 682 (-7700 4300)(-7700 4600);
WIRE 3 682 (-7700 4600)(-7800 4600);
WIRE 3 682 (-6750 4600)(-7050 4600);
WIRE 3 682 (-6750 4300)(-6750 4600);
WIRE 3 682 (-7050 4600)(-7050 4300);
WIRE 3 682 (-7050 4300)(-6750 4300);
WIRE 3 682 (-7250 3200)(-7250 2900);
WIRE 3 682 (-7250 2900)(-7150 2900);
WIRE 3 682 (-7150 3200)(-7250 3200);
WIRE 3 682 (-7150 3200)(-7150 2900);
WIRE 3 682 (-7450 2900)(-7350 2900);
WIRE 3 682 (-7450 3200)(-7450 2900);
WIRE 3 682 (-7350 2900)(-7350 3200);
WIRE 3 682 (-7350 3200)(-7450 3200);
WIRE 3 682 (-6950 3900)(-6950 3600);
WIRE 3 682 (-6850 3900)(-6950 3900);
WIRE 3 682 (-6950 3600)(-6850 3600);
WIRE 3 682 (-6850 3600)(-6850 3900);
WIRE 3 682 (-7050 3600)(-7050 3900);
WIRE 3 682 (-7150 3600)(-7050 3600);
WIRE 3 682 (-7050 3900)(-7150 3900);
WIRE 3 682 (-7150 3900)(-7150 3600);
WIRE 3 682 (-5200 4300)(-5200 4600);
WIRE 3 682 (-5300 4300)(-5200 4300);
WIRE 3 682 (-5200 4600)(-5300 4600);
WIRE 3 682 (-5300 4600)(-5300 4300);
WIRE 3 682 (-6500 2050)(-6500 2350);
WIRE 3 682 (-6600 2050)(-6500 2050);
WIRE 3 682 (-6500 2350)(-6600 2350);
WIRE 3 682 (-6600 2350)(-6600 2050);
WIRE 3 682 (-5250 700)(-5250 950);
WIRE 3 682 (-5450 700)(-5250 700);
WIRE 3 682 (-5250 950)(-5450 950);
WIRE 3 682 (-5450 950)(-5450 700);
WIRE 3 682 (-5700 950)(-5700 700);
WIRE 3 682 (-5500 950)(-5700 950);
WIRE 3 682 (-5700 700)(-5500 700);
WIRE 3 682 (-5500 700)(-5500 950);
WIRE 3 682 (-6900 1400)(-6800 1400);
WIRE 3 682 (-6900 1650)(-6900 1400);
WIRE 3 682 (-6800 1400)(-6800 1650);
WIRE 3 682 (-6800 1650)(-6900 1650);
WIRE 3 682 (-5700 1650)(-5700 1400);
WIRE 3 682 (-5250 1650)(-5700 1650);
WIRE 3 682 (-5700 1400)(-5250 1400);
WIRE 3 682 (-5250 1400)(-5250 1650);
WIRE 3 682 (-5600 2900)(-5500 2900);
WIRE 3 682 (-5600 3200)(-5600 2900);
WIRE 3 682 (-5500 2900)(-5500 3200);
WIRE 3 682 (-5500 3200)(-5600 3200);
DOT 1 (-4600 2050);
DOT 1 (-3100 2050);
DOT 1 (-7650 4250);
DOT 1 (-5150 2350);
DOT 1 (-5400 2350);
DOT 1 (-5900 3250);
DOT 1 (-1600 4625);
DOT 1 (-7450 600);
DOT 1 (-5900 3950);
DOT 1 (-5300 3950);
DOT 1 (-3250 3950);
DOT 1 (-2400 850);
DOT 1 (-2400 1350);
DOT 1 (-2700 850);
DOT 1 (-2700 1350);
DOT 1 (-3000 850);
DOT 1 (-3000 1350);
DOT 1 (-3300 850);
DOT 1 (-3300 1350);
DOT 1 (-5950 2400);
DOT 1 (-5950 2000);
DOT 1 (-7450 1300);
DOT 1 (-7450 2000);
DOT 1 (-7150 1000);
DOT 1 (-6850 600);
DOT 1 (-6850 1000);
DOT 1 (-7150 600);
DOT 1 (-7450 1000);
DOT 1 (-7450 1700);
DOT 1 (-7750 1000);
DOT 1 (-7750 600);
DOT 1 (-7750 1300);
DOT 1 (-7750 1700);
DOT 1 (-7150 2000);
DOT 1 (-7750 2000);
DOT 1 (-7150 2400);
DOT 1 (-7450 2400);
DOT 1 (-7750 2400);
DOT 1 (-7050 2850);
DOT 1 (-1975 3950);
DOT 1 (-1475 3550);
DOT 1 (-1225 3550);
DOT 1 (-1475 3950);
DOT 1 (-975 3550);
DOT 1 (-750 3550);
DOT 1 (-2650 3550);
DOT 1 (-2650 3950);
DOT 1 (-2950 3550);
DOT 1 (-3250 3550);
DOT 1 (-3850 3550);
DOT 1 (-3550 3550);
DOT 1 (-3550 3950);
DOT 1 (-3850 3950);
DOT 1 (-2725 4250);
DOT 1 (-3950 2850);
DOT 1 (-1875 4250);
DOT 1 (-725 4250);
DOT 1 (-975 4250);
DOT 1 (-975 4625);
DOT 1 (-1275 4625);
DOT 1 (-2175 4625);
DOT 1 (-2450 4625);
DOT 1 (-2725 4625);
DOT 1 (-3250 4250);
DOT 1 (-3250 4625);
DOT 1 (-3500 4625);
DOT 1 (-1600 4250);
DOT 1 (-1875 4625);
DOT 1 (-1275 4250);
DOT 1 (-2450 4250);
DOT 1 (-2975 4250);
DOT 1 (-3500 4250);
DOT 1 (-7650 4650);
DOT 1 (-7350 4650);
DOT 1 (-7750 3950);
DOT 1 (-7750 3550);
DOT 1 (-7350 4250);
DOT 1 (-7450 3950);
DOT 1 (-7450 3550);
DOT 1 (-7750 3250);
DOT 1 (-7750 2850);
DOT 1 (-7050 3250);
DOT 1 (-5900 4250);
DOT 1 (-5600 4650);
DOT 1 (-5900 4650);
DOT 1 (-5600 4250);
DOT 1 (-5100 4650);
DOT 1 (-5100 4250);
DOT 1 (-4800 4650);
DOT 1 (-4800 4250);
DOT 1 (-3750 4250);
DOT 1 (-5900 3550);
DOT 1 (-5900 2850);
DOT 1 (-5400 3250);
DOT 1 (-5400 2850);
DOT 1 (-5100 2850);
DOT 1 (-4800 3250);
DOT 1 (-5600 3950);
DOT 1 (-5600 3550);
DOT 1 (-5300 3550);
DOT 1 (-5000 3950);
DOT 1 (-4700 3950);
DOT 1 (-4700 3550);
DOT 1 (-5000 3550);
DOT 1 (-4800 2850);
DOT 1 (-5100 3250);
DOT 1 (-3950 850);
DOT 1 (-4250 1350);
DOT 1 (-4550 1350);
DOT 1 (-4250 850);
DOT 1 (-1725 3950);
DOT 1 (-3950 3300);
DOT 1 (-3650 3300);
DOT 1 (-3350 3300);
DOT 1 (-3350 2850);
DOT 1 (-1100 2850);
DOT 1 (-1400 3250);
DOT 1 (-850 2400);
DOT 1 (-1100 2400);
DOT 1 (-1350 2400);
DOT 1 (-1600 2400);
DOT 1 (-1850 2400);
DOT 1 (-2100 2400);
DOT 1 (-2350 2400);
DOT 1 (-2850 2400);
DOT 1 (-3100 2400);
DOT 1 (-3850 2400);
DOT 1 (-4600 2400);
DOT 1 (-2175 4250);
DOT 1 (-2950 3950);
DOT 1 (-1225 3950);
DOT 1 (-4000 4625);
DOT 1 (-3750 4625);
DOT 1 (-2975 4625);
DOT 1 (-1725 3550);
DOT 1 (-975 3950);
DOT 1 (-3350 2400);
DOT 1 (-4350 2400);
DOT 1 (-3600 2050);
DOT 1 (-3350 2050);
DOT 1 (-2850 2050);
DOT 1 (-2100 2050);
DOT 1 (-1600 2050);
DOT 1 (-1850 2050);
DOT 1 (-1350 2050);
DOT 1 (-850 2050);
DOT 1 (-3850 2050);
DOT 1 (-2600 2050);
DOT 1 (-2350 2050);
DOT 1 (-1100 2050);
DOT 1 (-2600 2400);
DOT 1 (-4100 2400);
DOT 1 (-4100 2050);
DOT 1 (-4350 2050);
DOT 1 (-3600 2400);
DOT 1 (-3650 2850);
FORCENOTE
PVCCIO: 47UF/805/3X, 22UF/603/2X
(-3140 1390) 0;
DISPLAY LEFT (-3140 1390);
PAINT PURPLE (-3140 1390);
FORCENOTE
TP FAB1 ADD CAP 0314
(-1400 950) 0;
DISPLAY LEFT (-1400 950);
DISPLAY 0.638298 (-1400 950);
PAINT RED (-1400 950);
FORCENOTE
TP FAB1 MOVE TO PAGE 228 0314
(-7725 4650) 0;
DISPLAY LEFT (-7725 4650);
DISPLAY 0.638298 (-7725 4650);
PAINT RED (-7725 4650);
FORCENOTE
PVMCP: 22UF, 603, 21X
(-2515 4790) 0;
DISPLAY LEFT (-2515 4790);
PAINT PURPLE (-2515 4790);
FORCENOTE
(DEBUG ONLY)
(-2464 4707) 0;
DISPLAY LEFT (-2464 4707);
DISPLAY 1.021277 (-2464 4707);
PAINT PURPLE (-2464 4707);
FORCENOTE
PVCCIO: 22UF, 603, 6X
(-3340 4015) 0;
DISPLAY LEFT (-3340 4015);
PAINT PURPLE (-3340 4015);
FORCENOTE
TP FAB1 MOVE TO PAGE 228 0311
(-5750 1675) 0;
DISPLAY LEFT (-5750 1675);
DISPLAY 0.638298 (-5750 1675);
PAINT RED (-5750 1675);
FORCENOTE
TP FAB1 MOVE TO PAGE 225 0314
(-5800 3275) 0;
DISPLAY LEFT (-5800 3275);
DISPLAY 0.638298 (-5800 3275);
PAINT RED (-5800 3275);
FORCENOTE
PVCCIN: 47UF, 805, 17X
(-7140 2465) 0;
DISPLAY LEFT (-7140 2465);
PAINT PURPLE (-7140 2465);
FORCENOTE
TP FAB1 MOVE TO PAGE 225 0311
(-6650 2400) 0;
DISPLAY LEFT (-6650 2400);
DISPLAY 0.638298 (-6650 2400);
PAINT RED (-6650 2400);
FORCENOTE
TP FAB1 MOVE TO PAGE 225 0311
(-7000 1725) 0;
DISPLAY LEFT (-7000 1725);
DISPLAY 0.638298 (-7000 1725);
PAINT RED (-7000 1725);
FORCENOTE
PVCCIN: 22UF/603/25X
(-7440 4765) 0;
DISPLAY LEFT (-7440 4765);
PAINT PURPLE (-7440 4765);
FORCENOTE
TP FAB1 MOVE TO PAGE 228 0314
(-7075 4650) 0;
DISPLAY LEFT (-7075 4650);
DISPLAY 0.638298 (-7075 4650);
PAINT RED (-7075 4650);
FORCENOTE
TP FAB1 MOVE TO PAGE 225 0314
(-7225 3950) 0;
DISPLAY LEFT (-7225 3950);
DISPLAY 0.638298 (-7225 3950);
PAINT RED (-7225 3950);
FORCENOTE
TP FAB1 MOVE TO PAGE 228 0314
(-7475 4000) 0;
DISPLAY LEFT (-7475 4000);
DISPLAY 0.638298 (-7475 4000);
PAINT RED (-7475 4000);
FORCENOTE
TP FAB1 MOVE TO PAGE 225 0311
(-5800 1050) 0;
DISPLAY LEFT (-5800 1050);
DISPLAY 0.638298 (-5800 1050);
PAINT RED (-5800 1050);
FORCENOTE
TP FAB1 MOVE TO PAGE 228 0318
(-5600 975) 0;
DISPLAY LEFT (-5600 975);
DISPLAY 0.638298 (-5600 975);
PAINT RED (-5600 975);
FORCENOTE
ROOM = PVCCIN_CPU1_DECAP_VR
(-7890 190) 0;
DISPLAY LEFT (-7890 190);
DISPLAY 2.446809 (-7890 190);
PAINT PURPLE (-7890 190);
FORCENOTE
TP FAB1 MOVE TO PAGE 228 0314
(-7550 3250) 0;
DISPLAY LEFT (-7550 3250);
DISPLAY 0.638298 (-7550 3250);
PAINT RED (-7550 3250);
FORCENOTE
TP FAB1 MOVE TO PAGE 225 0314
(-7650 3300) 0;
DISPLAY LEFT (-7650 3300);
DISPLAY 0.638298 (-7650 3300);
PAINT RED (-7650 3300);
FORCENOTE
TP FAB1 MOVE TO PAGE 225 0314
(-5575 4675) 0;
DISPLAY LEFT (-5575 4675);
DISPLAY 0.638298 (-5575 4675);
PAINT RED (-5575 4675);
FORCENOTE
TP FAB1 MOVE TO PAGE 228 0311
(-5550 2525) 0;
DISPLAY LEFT (-5550 2525);
DISPLAY 0.638298 (-5550 2525);
PAINT RED (-5550 2525);
FORCENOTE
TP FAB1 MOVE TO PAGE 225 0318
(-5550 2450) 0;
DISPLAY LEFT (-5550 2450);
DISPLAY 0.638298 (-5550 2450);
PAINT RED (-5550 2450);
FORCENOTE
FULL CAP CONFIG FOR -P SUPPORT.
(-1365 490) 0;
DISPLAY LEFT (-1365 490);
PAINT PURPLE (-1365 490);
FORCENOTE
FULL CAP CONFIG FOR -P SUPPORT.
(-2615 2865) 0;
DISPLAY LEFT (-2615 2865);
PAINT PURPLE (-2615 2865);
FORCENOTE
REMOVE DURING MASS PRODUCTION
(-2475 2500) 0;
DISPLAY LEFT (-2475 2500);
DISPLAY 1.021277 (-2475 2500);
PAINT PURPLE (-2475 2500);
FORCENOTE
(DEBUG ONLY)
(-3180 2429) 0;
DISPLAY LEFT (-3180 2429);
DISPLAY 1.021277 (-3180 2429);
PAINT PURPLE (-3180 2429);
FORCENOTE
PVMCP: 100UF, 805, 17X
(-3340 2515) 0;
DISPLAY LEFT (-3340 2515);
PAINT PURPLE (-3340 2515);
FORCENOTE
TP FAB3 ADD CAP 0919
(-1550 2700) 0;
DISPLAY LEFT (-1550 2700);
DISPLAY 0.638298 (-1550 2700);
PAINT RED (-1550 2700);
FORCENOTE
TP FAB4 ADD ATTRIBUTE GROUP=PWR_MCP_CAP 20170508
(-4800 1600) 0;
DISPLAY LEFT (-4800 1600);
DISPLAY 0.638298 (-4800 1600);
PAINT RED (-4800 1600);
FORCENOTE
TP FAB3 CHANGE CAP FROM 47UF TO 100UF 1004
(-4800 1650) 0;
DISPLAY LEFT (-4800 1650);
DISPLAY 0.638298 (-4800 1650);
PAINT RED (-4800 1650);
QUIT
